FILE_TYPE = MACRO_DRAWING;
SET COLOR_WIRE YELLOW;
SET COLOR_PROP MONO;
SET COLOR_DOT WHITE;
SET COLOR_ARC YELLOW;
SET COLOR_BODY GREEN;
SET COLOR_NOTE MONO;
SET PROP_DISPLAY VALUE;
SET PAGE_NUMBER P22;
FORCEADD OFFPAGE..4
(-1675 2850);
FORCEPROP 2 LAST $XR0 111 
J 0
(-1489 2850);
DISPLAY 0.638298 (-1489 2850);
PAINT MONO (-1489 2850);
FORCEPROP 2 LAST $XR1 118 
J 0
(-1369 2850);
DISPLAY 0.638298 (-1369 2850);
PAINT MONO (-1369 2850);
FORCEPROP 2 LAST $XR2 56 
J 0
(-1249 2850);
DISPLAY 0.638298 (-1249 2850);
PAINT MONO (-1249 2850);
FORCEPROP 2 LAST CDS_LIB mstr_standard
J 0
(-1675 2850);
DISPLAY 0.787234 (-1675 2850);
PAINT MONO (-1675 2850);
DISPLAY INVISIBLE (-1675 2850);
FORCEPROP 1 LAST OFFPAGE TRUE
J 0
(-1350 2725);
DISPLAY 0.680851 (-1350 2725);
PAINT GREEN (-1350 2725);
DISPLAY INVISIBLE (-1350 2725);
FORCEPROP 1 LAST COMMENT_BODY TRUE
J 0
(-1700 2750);
DISPLAY 0.680851 (-1700 2750);
PAINT PEACH (-1700 2750);
DISPLAY INVISIBLE (-1700 2750);
FORCEPROP 2 LAST PATH I185
J 0
(-1350 2900);
DISPLAY 1.021277 (-1350 2900);
PAINT ORANGE (-1350 2900);
DISPLAY INVISIBLE (-1350 2900);
FORCEADD OFFPAGE..4
(-1675 1850);
FORCEPROP 2 LAST $XR0 104 
J 0
(-1489 1850);
DISPLAY 0.638298 (-1489 1850);
PAINT MONO (-1489 1850);
FORCEPROP 2 LAST CDS_LIB mstr_standard
J 0
(-1675 1850);
PAINT ORANGE (-1675 1850);
DISPLAY INVISIBLE (-1675 1850);
FORCEPROP 1 LAST OFFPAGE TRUE
J 0
(-1350 1725);
DISPLAY 0.872340 (-1350 1725);
PAINT GREEN (-1350 1725);
DISPLAY INVISIBLE (-1350 1725);
FORCEPROP 1 LAST COMMENT_BODY TRUE
J 0
(-1700 1750);
DISPLAY 0.872340 (-1700 1750);
PAINT GREEN (-1700 1750);
DISPLAY INVISIBLE (-1700 1750);
FORCEPROP 2 LAST PATH I186
J 0
(-1475 1900);
DISPLAY 1.021277 (-1475 1900);
PAINT ORANGE (-1475 1900);
DISPLAY INVISIBLE (-1475 1900);
FORCEADD RES..2
(-300 2775);
FORCEPROP 1 LAST LOCATION R5R1
J 0
(-255 2900);
DISPLAY 0.617021 (-255 2900);
PAINT AQUA (-255 2900);
FORCEPROP 1 LAST PART_NUMBER G21796-047
J 0
(-260 2650);
DISPLAY 0.617021 (-260 2650);
PAINT BLUE (-260 2650);
FORCEPROP 1 LAST VALUE 49.9
J 0
(-255 2850);
DISPLAY 0.617021 (-255 2850);
PAINT SKYBLUE (-255 2850);
FORCEPROP 1 LAST TOLERANCE 1%
J 0
(-255 2800);
DISPLAY 0.617021 (-255 2800);
PAINT SKYBLUE (-255 2800);
FORCEPROP 1 LAST PACK_TYPE 0402
J 0
(-260 2600);
DISPLAY 0.617021 (-260 2600);
PAINT SKYBLUE (-260 2600);
FORCEPROP 1 LAST MATERIAL CHIP
J 0
(-260 2700);
DISPLAY 0.617021 (-260 2700);
PAINT SKYBLUE (-260 2700);
FORCEPROP 1 LAST WATTAGE 1/16W
J 0
(-260 2750);
DISPLAY 0.617021 (-260 2750);
PAINT SKYBLUE (-260 2750);
FORCEPROP 1 LASTPIN (-300 2675) $PN 2
J 0
(-295 2685);
DISPLAY 0.617021 (-295 2685);
PAINT ORANGE (-295 2685);
FORCEPROP 1 LASTPIN (-300 2875) $PN 1
J 0
(-295 2837);
DISPLAY 0.617021 (-295 2837);
PAINT ORANGE (-295 2837);
FORCEPROP 2 LAST SEC_TYPE 0402
J 0
(-250 3000);
DISPLAY 1.021277 (-250 3000);
PAINT ORANGE (-250 3000);
DISPLAY INVISIBLE (-250 3000);
FORCEPROP 2 LAST CDS_LIB mstr_discrete
J 0
(-300 2775);
PAINT MONO (-300 2775);
DISPLAY INVISIBLE (-300 2775);
FORCEPROP 2 LAST SEC 1
J 0
(-250 3000);
DISPLAY 0.680851 (-250 3000);
PAINT MONO (-250 3000);
DISPLAY INVISIBLE (-250 3000);
FORCEPROP 2 LAST CDS_LOCATION R5R1
J 0
(-255 2900);
DISPLAY 0.617021 (-255 2900);
PAINT AQUA (-255 2900);
DISPLAY INVISIBLE (-255 2900);
FORCEPROP 1 LAST PATH I188
J 0
(-250 2950);
DISPLAY 0.978723 (-250 2950);
PAINT WHITE (-250 2950);
DISPLAY INVISIBLE (-250 2950);
FORCEPROP 0 LAST ROOM CPU0
J 0
(-250 3000);
DISPLAY 1.021277 (-250 3000);
PAINT ORANGE (-250 3000);
DISPLAY INVISIBLE (-250 3000);
FORCEADD GND..1
(-300 2450);
FORCEPROP 3 LASTPIN (-300 2500) SIG_NAME GND\g
J 0
(-290 2510);
DISPLAY 0.659574 (-290 2510);
PAINT MONO (-290 2510);
DISPLAY INVISIBLE (-290 2510);
FORCEPROP 1 LAST VOLTAGE 0.0V
J 0
(-345 2407);
DISPLAY 0.340426 (-345 2407);
PAINT SKYBLUE (-345 2407);
DISPLAY INVISIBLE (-345 2407);
FORCEPROP 2 LAST CDS_LIB mstr_symbols
J 0
(-300 2450);
PAINT MONO (-300 2450);
DISPLAY INVISIBLE (-300 2450);
FORCEPROP 1 LAST SIZE 1B
J 0
(-225 2400);
DISPLAY 1.170213 (-225 2400);
PAINT GREEN (-225 2400);
DISPLAY INVISIBLE (-225 2400);
FORCEPROP 1 LAST BODY_TYPE PLUMBING
J 0
(-345 2407);
DISPLAY 0.340426 (-345 2407);
PAINT GREEN (-345 2407);
DISPLAY INVISIBLE (-345 2407);
FORCEPROP 1 LAST PATH I189
J 0
(-225 2450);
DISPLAY 0.872340 (-225 2450);
PAINT AQUA (-225 2450);
DISPLAY INVISIBLE (-225 2450);
FORCEPROP 1 LAST HDL_POWER GND
J 0
(-300 2600);
DISPLAY 0.702128 (-300 2600);
PAINT GREEN (-300 2600);
DISPLAY INVISIBLE (-300 2600);
FORCEADD RES..2
(-575 2775);
FORCEPROP 1 LAST LOCATION R5P4
J 0
(-530 2900);
DISPLAY 0.617021 (-530 2900);
PAINT AQUA (-530 2900);
FORCEPROP 1 LAST PART_NUMBER G21796-047
J 0
(-535 2650);
DISPLAY 0.617021 (-535 2650);
PAINT BLUE (-535 2650);
FORCEPROP 1 LAST VALUE 49.9
J 0
(-530 2850);
DISPLAY 0.617021 (-530 2850);
PAINT SKYBLUE (-530 2850);
FORCEPROP 1 LAST TOLERANCE 1%
J 0
(-530 2800);
DISPLAY 0.617021 (-530 2800);
PAINT SKYBLUE (-530 2800);
FORCEPROP 1 LAST PACK_TYPE 0402
J 0
(-535 2600);
DISPLAY 0.617021 (-535 2600);
PAINT SKYBLUE (-535 2600);
FORCEPROP 1 LAST MATERIAL CHIP
J 0
(-535 2700);
DISPLAY 0.617021 (-535 2700);
PAINT SKYBLUE (-535 2700);
FORCEPROP 1 LAST WATTAGE 1/16W
J 0
(-535 2750);
DISPLAY 0.617021 (-535 2750);
PAINT SKYBLUE (-535 2750);
FORCEPROP 1 LASTPIN (-575 2675) $PN 2
J 0
(-570 2685);
DISPLAY 0.617021 (-570 2685);
PAINT ORANGE (-570 2685);
FORCEPROP 1 LASTPIN (-575 2875) $PN 1
J 0
(-570 2837);
DISPLAY 0.617021 (-570 2837);
PAINT ORANGE (-570 2837);
FORCEPROP 2 LAST SEC_TYPE 0402
J 0
(-525 3000);
DISPLAY 1.021277 (-525 3000);
PAINT ORANGE (-525 3000);
DISPLAY INVISIBLE (-525 3000);
FORCEPROP 2 LAST CDS_LIB mstr_discrete
J 0
(-575 2775);
PAINT MONO (-575 2775);
DISPLAY INVISIBLE (-575 2775);
FORCEPROP 2 LAST SEC 1
J 0
(-525 3000);
DISPLAY 0.680851 (-525 3000);
PAINT MONO (-525 3000);
DISPLAY INVISIBLE (-525 3000);
FORCEPROP 2 LAST CDS_LOCATION R5P4
J 0
(-530 2900);
DISPLAY 0.617021 (-530 2900);
PAINT AQUA (-530 2900);
DISPLAY INVISIBLE (-530 2900);
FORCEPROP 1 LAST PATH I190
J 0
(-525 2950);
DISPLAY 0.978723 (-525 2950);
PAINT WHITE (-525 2950);
DISPLAY INVISIBLE (-525 2950);
FORCEPROP 0 LAST ROOM CPU0
J 0
(-525 3000);
DISPLAY 1.021277 (-525 3000);
PAINT ORANGE (-525 3000);
DISPLAY INVISIBLE (-525 3000);
FORCEADD OFFPAGE..4
(-1675 2050);
FORCEPROP 2 LAST $XR0 90 
J 0
(-1489 2050);
DISPLAY 0.638298 (-1489 2050);
PAINT MONO (-1489 2050);
FORCEPROP 2 LAST CDS_LIB mstr_standard
J 0
(-1675 2050);
DISPLAY 0.489362 (-1675 2050);
PAINT ORANGE (-1675 2050);
DISPLAY INVISIBLE (-1675 2050);
FORCEPROP 1 LAST OFFPAGE TRUE
J 0
(-1350 1925);
DISPLAY 0.680851 (-1350 1925);
PAINT GREEN (-1350 1925);
DISPLAY INVISIBLE (-1350 1925);
FORCEPROP 1 LAST COMMENT_BODY TRUE
J 0
(-1700 1950);
DISPLAY 0.680851 (-1700 1950);
PAINT PEACH (-1700 1950);
DISPLAY INVISIBLE (-1700 1950);
FORCEPROP 2 LAST PATH I195
J 0
(-1475 2100);
DISPLAY 1.021277 (-1475 2100);
PAINT ORANGE (-1475 2100);
DISPLAY INVISIBLE (-1475 2100);
FORCEADD OFFPAGE..2
(-1675 2650);
FORCEPROP 2 LAST $XR0 92 
J 0
(-1486 2650);
DISPLAY 0.638298 (-1486 2650);
PAINT MONO (-1486 2650);
FORCEPROP 2 LAST CDS_LIB mstr_standard
J 0
(-1675 2650);
PAINT MONO (-1675 2650);
DISPLAY INVISIBLE (-1675 2650);
FORCEPROP 1 LAST OFFPAGE TRUE
J 0
(-1350 2525);
DISPLAY 0.489362 (-1350 2525);
PAINT GREEN (-1350 2525);
DISPLAY INVISIBLE (-1350 2525);
FORCEPROP 1 LAST COMMENT_BODY TRUE
J 0
(-1720 2555);
DISPLAY 0.936170 (-1720 2555);
PAINT PEACH (-1720 2555);
DISPLAY INVISIBLE (-1720 2555);
FORCEPROP 2 LAST PATH I196
J 0
(-1500 2725);
DISPLAY 1.021277 (-1500 2725);
PAINT ORANGE (-1500 2725);
DISPLAY INVISIBLE (-1500 2725);
FORCEADD OFFPAGE..4
(-1675 2450);
FORCEPROP 2 LAST $XR0 111 
J 0
(-1489 2450);
DISPLAY 0.638298 (-1489 2450);
PAINT MONO (-1489 2450);
FORCEPROP 2 LAST $XR1 56 
J 0
(-1369 2450);
DISPLAY 0.638298 (-1369 2450);
PAINT MONO (-1369 2450);
FORCEPROP 2 LAST CDS_LIB mstr_standard
J 0
(-1675 2450);
DISPLAY 0.787234 (-1675 2450);
PAINT MONO (-1675 2450);
DISPLAY INVISIBLE (-1675 2450);
FORCEPROP 1 LAST OFFPAGE TRUE
J 0
(-1350 2325);
DISPLAY 0.680851 (-1350 2325);
PAINT GREEN (-1350 2325);
DISPLAY INVISIBLE (-1350 2325);
FORCEPROP 1 LAST COMMENT_BODY TRUE
J 0
(-1700 2350);
DISPLAY 0.680851 (-1700 2350);
PAINT PEACH (-1700 2350);
DISPLAY INVISIBLE (-1700 2350);
FORCEPROP 2 LAST PATH I197
J 0
(-1350 2500);
DISPLAY 1.021277 (-1350 2500);
PAINT ORANGE (-1350 2500);
DISPLAY INVISIBLE (-1350 2500);
FORCEADD OFFPAGE..4
(-1675 2700);
FORCEPROP 2 LAST $XR0 104 
J 0
(-1489 2700);
DISPLAY 0.638298 (-1489 2700);
PAINT MONO (-1489 2700);
FORCEPROP 2 LAST CDS_LIB mstr_standard
J 0
(-1675 2700);
PAINT MONO (-1675 2700);
DISPLAY INVISIBLE (-1675 2700);
FORCEPROP 1 LAST OFFPAGE TRUE
J 0
(-1350 2575);
DISPLAY 0.680851 (-1350 2575);
PAINT GREEN (-1350 2575);
DISPLAY INVISIBLE (-1350 2575);
FORCEPROP 1 LAST COMMENT_BODY TRUE
J 0
(-1700 2600);
DISPLAY 0.680851 (-1700 2600);
PAINT PEACH (-1700 2600);
DISPLAY INVISIBLE (-1700 2600);
FORCEPROP 2 LAST PATH I198
J 0
(-1500 2775);
DISPLAY 1.021277 (-1500 2775);
PAINT ORANGE (-1500 2775);
DISPLAY INVISIBLE (-1500 2775);
FORCEADD OFFPAGE..4
(-1675 1450);
FORCEPROP 2 LAST $XR0 103 
J 0
(-1489 1450);
DISPLAY 0.638298 (-1489 1450);
PAINT MONO (-1489 1450);
FORCEPROP 2 LAST CDS_LIB mstr_standard
J 0
(-1675 1450);
PAINT MONO (-1675 1450);
DISPLAY INVISIBLE (-1675 1450);
FORCEPROP 1 LAST OFFPAGE TRUE
J 0
(-1350 1325);
DISPLAY 0.872340 (-1350 1325);
PAINT GREEN (-1350 1325);
DISPLAY INVISIBLE (-1350 1325);
FORCEPROP 1 LAST COMMENT_BODY TRUE
J 0
(-1700 1350);
DISPLAY 0.872340 (-1700 1350);
PAINT GREEN (-1700 1350);
DISPLAY INVISIBLE (-1700 1350);
FORCEPROP 2 LAST PATH I199
J 0
(-1500 1525);
DISPLAY 1.021277 (-1500 1525);
PAINT ORANGE (-1500 1525);
DISPLAY INVISIBLE (-1500 1525);
FORCEADD OFFPAGE..4
(-1675 850);
FORCEPROP 2 LAST $XR0 103 
J 0
(-1489 850);
DISPLAY 0.638298 (-1489 850);
PAINT MONO (-1489 850);
FORCEPROP 2 LAST CDS_LIB mstr_standard
J 0
(-1675 850);
PAINT MONO (-1675 850);
DISPLAY INVISIBLE (-1675 850);
FORCEPROP 1 LAST OFFPAGE TRUE
J 0
(-1350 725);
DISPLAY 0.872340 (-1350 725);
PAINT GREEN (-1350 725);
DISPLAY INVISIBLE (-1350 725);
FORCEPROP 1 LAST COMMENT_BODY TRUE
J 0
(-1700 750);
DISPLAY 0.872340 (-1700 750);
PAINT GREEN (-1700 750);
DISPLAY INVISIBLE (-1700 750);
FORCEPROP 2 LAST PATH I200
J 0
(-1500 925);
DISPLAY 1.021277 (-1500 925);
PAINT ORANGE (-1500 925);
DISPLAY INVISIBLE (-1500 925);
FORCEADD VCC_CORE..1
(-1100 2325);
FORCEPROP 3 LASTPIN (-1100 2275) SIG_NAME PVCCMCP_CPU0\g
J 0
(-1090 2285);
DISPLAY 0.659574 (-1090 2285);
PAINT MONO (-1090 2285);
DISPLAY INVISIBLE (-1090 2285);
FORCEPROP 1 LAST HDL_POWER PVCCMCP_CPU0
J 1
(-1100 2375);
DISPLAY 0.617021 (-1100 2375);
PAINT GREEN (-1100 2375);
FORCEPROP 2 LAST CDS_LIB mstr_symbols
J 0
(-1100 2325);
PAINT ORANGE (-1100 2325);
DISPLAY INVISIBLE (-1100 2325);
FORCEPROP 1 LAST PATH I202
J 0
(-1050 2350);
DISPLAY 0.872340 (-1050 2350);
PAINT AQUA (-1050 2350);
DISPLAY INVISIBLE (-1050 2350);
FORCEADD VCC_CORE..1
(-7300 4475);
FORCEPROP 3 LASTPIN (-7300 4425) SIG_NAME P1V8_MCP_CPU0\g
J 0
(-7290 4435);
DISPLAY 0.659574 (-7290 4435);
PAINT MONO (-7290 4435);
DISPLAY INVISIBLE (-7290 4435);
FORCEPROP 1 LAST HDL_POWER P1V8_MCP_CPU0
J 1
(-7300 4525);
DISPLAY 0.617021 (-7300 4525);
PAINT GREEN (-7300 4525);
FORCEPROP 2 LAST CDS_LIB mstr_symbols
J 0
(-7300 4475);
PAINT ORANGE (-7300 4475);
DISPLAY INVISIBLE (-7300 4475);
FORCEPROP 1 LAST PATH I203
J 0
(-7250 4500);
DISPLAY 0.872340 (-7250 4500);
PAINT AQUA (-7250 4500);
DISPLAY INVISIBLE (-7250 4500);
FORCEADD SKX_EXT_B..2
(-4150 2550);
FORCEPROP 1 LAST LOCATION U5D1
J 0
(-5350 4600);
DISPLAY 0.617021 (-5350 4600);
PAINT AQUA (-5350 4600);
FORCEPROP 1 LAST PART_NUMBER TBD
J 0
(-5350 550);
DISPLAY 0.617021 (-5350 550);
PAINT BLUE (-5350 550);
FORCEPROP 1 LAST MATERIAL IC
J 0
(-5350 4550);
DISPLAY 0.617021 (-5350 4550);
PAINT SKYBLUE (-5350 4550);
FORCEPROP 2 LASTPIN (-5400 1600) $PN AY13
J 2
(-5410 1610);
DISPLAY 0.617021 (-5410 1610);
PAINT ORANGE (-5410 1610);
FORCEPROP 2 LASTPIN (-2900 2350) $PN AN14
J 0
(-2890 2360);
DISPLAY 0.617021 (-2890 2360);
PAINT ORANGE (-2890 2360);
FORCEPROP 2 LASTPIN (-2900 2950) $PN AN12
J 0
(-2890 2960);
DISPLAY 0.617021 (-2890 2960);
PAINT ORANGE (-2890 2960);
FORCEPROP 2 LASTPIN (-2900 3000) $PN AM13
J 0
(-2890 3010);
DISPLAY 0.617021 (-2890 3010);
PAINT ORANGE (-2890 3010);
FORCEPROP 2 LASTPIN (-2900 3050) $PN AG46
J 0
(-2890 3060);
DISPLAY 0.617021 (-2890 3060);
PAINT ORANGE (-2890 3060);
FORCEPROP 2 LASTPIN (-2900 3100) $PN AF45
J 0
(-2890 3110);
DISPLAY 0.617021 (-2890 3110);
PAINT ORANGE (-2890 3110);
FORCEPROP 2 LASTPIN (-5400 4350) $PN A4
J 2
(-5410 4360);
DISPLAY 0.617021 (-5410 4360);
PAINT ORANGE (-5410 4360);
FORCEPROP 2 LASTPIN (-5400 4300) $PN A6
J 2
(-5410 4310);
DISPLAY 0.617021 (-5410 4310);
PAINT ORANGE (-5410 4310);
FORCEPROP 2 LASTPIN (-5400 4250) $PN A14
J 2
(-5410 4260);
DISPLAY 0.617021 (-5410 4260);
PAINT ORANGE (-5410 4260);
FORCEPROP 2 LASTPIN (-5400 4200) $PN A16
J 2
(-5410 4210);
DISPLAY 0.617021 (-5410 4210);
PAINT ORANGE (-5410 4210);
FORCEPROP 2 LASTPIN (-5400 4150) $PN A24
J 2
(-5410 4160);
DISPLAY 0.617021 (-5410 4160);
PAINT ORANGE (-5410 4160);
FORCEPROP 2 LASTPIN (-5400 4100) $PN B3
J 2
(-5410 4110);
DISPLAY 0.617021 (-5410 4110);
PAINT ORANGE (-5410 4110);
FORCEPROP 2 LASTPIN (-5400 4050) $PN B7
J 2
(-5410 4060);
DISPLAY 0.617021 (-5410 4060);
PAINT ORANGE (-5410 4060);
FORCEPROP 2 LASTPIN (-5400 3950) $PN B13
J 2
(-5410 3960);
DISPLAY 0.617021 (-5410 3960);
PAINT ORANGE (-5410 3960);
FORCEPROP 2 LASTPIN (-5400 3900) $PN B15
J 2
(-5410 3910);
DISPLAY 0.617021 (-5410 3910);
PAINT ORANGE (-5410 3910);
FORCEPROP 2 LASTPIN (-5400 3850) $PN B17
J 2
(-5410 3860);
DISPLAY 0.617021 (-5410 3860);
PAINT ORANGE (-5410 3860);
FORCEPROP 2 LASTPIN (-5400 3800) $PN B77
J 2
(-5410 3810);
DISPLAY 0.617021 (-5410 3810);
PAINT ORANGE (-5410 3810);
FORCEPROP 2 LASTPIN (-5400 3750) $PN B81
J 2
(-5410 3760);
DISPLAY 0.617021 (-5410 3760);
PAINT ORANGE (-5410 3760);
FORCEPROP 2 LASTPIN (-5400 3700) $PN C6
J 2
(-5410 3710);
DISPLAY 0.617021 (-5410 3710);
PAINT ORANGE (-5410 3710);
FORCEPROP 2 LASTPIN (-5400 3650) $PN C18
J 2
(-5410 3660);
DISPLAY 0.617021 (-5410 3660);
PAINT ORANGE (-5410 3660);
FORCEPROP 2 LASTPIN (-5400 3550) $PN C24
J 2
(-5410 3560);
DISPLAY 0.617021 (-5410 3560);
PAINT ORANGE (-5410 3560);
FORCEPROP 2 LASTPIN (-5400 3500) $PN C82
J 2
(-5410 3510);
DISPLAY 0.617021 (-5410 3510);
PAINT ORANGE (-5410 3510);
FORCEPROP 2 LASTPIN (-5400 3450) $PN D5
J 2
(-5410 3460);
DISPLAY 0.617021 (-5410 3460);
PAINT ORANGE (-5410 3460);
FORCEPROP 2 LASTPIN (-5400 3400) $PN D17
J 2
(-5410 3410);
DISPLAY 0.617021 (-5410 3410);
PAINT ORANGE (-5410 3410);
FORCEPROP 2 LASTPIN (-5400 3350) $PN D65
J 2
(-5410 3360);
DISPLAY 0.617021 (-5410 3360);
PAINT ORANGE (-5410 3360);
FORCEPROP 2 LASTPIN (-5400 3300) $PN D83
J 2
(-5410 3310);
DISPLAY 0.617021 (-5410 3310);
PAINT ORANGE (-5410 3310);
FORCEPROP 2 LASTPIN (-5400 3250) $PN E2
J 2
(-5410 3260);
DISPLAY 0.617021 (-5410 3260);
PAINT ORANGE (-5410 3260);
FORCEPROP 2 LASTPIN (-5400 3200) $PN E4
J 2
(-5410 3210);
DISPLAY 0.617021 (-5410 3210);
PAINT ORANGE (-5410 3210);
FORCEPROP 2 LASTPIN (-5400 3100) $PN E24
J 2
(-5410 3110);
DISPLAY 0.617021 (-5410 3110);
PAINT ORANGE (-5410 3110);
FORCEPROP 2 LASTPIN (-5400 3050) $PN E84
J 2
(-5410 3060);
DISPLAY 0.617021 (-5410 3060);
PAINT ORANGE (-5410 3060);
FORCEPROP 2 LASTPIN (-5400 3000) $PN F3
J 2
(-5410 3010);
DISPLAY 0.617021 (-5410 3010);
PAINT ORANGE (-5410 3010);
FORCEPROP 2 LASTPIN (-5400 2950) $PN F23
J 2
(-5410 2960);
DISPLAY 0.617021 (-5410 2960);
PAINT ORANGE (-5410 2960);
FORCEPROP 2 LASTPIN (-5400 2850) $PN F65
J 2
(-5410 2860);
DISPLAY 0.617021 (-5410 2860);
PAINT ORANGE (-5410 2860);
FORCEPROP 2 LASTPIN (-5400 2800) $PN F83
J 2
(-5410 2810);
DISPLAY 0.617021 (-5410 2810);
PAINT ORANGE (-5410 2810);
FORCEPROP 2 LASTPIN (-5400 2700) $PN G2
J 2
(-5410 2710);
DISPLAY 0.617021 (-5410 2710);
PAINT ORANGE (-5410 2710);
FORCEPROP 2 LASTPIN (-5400 2650) $PN G64
J 2
(-5410 2660);
DISPLAY 0.617021 (-5410 2660);
PAINT ORANGE (-5410 2660);
FORCEPROP 2 LASTPIN (-5400 2600) $PN G84
J 2
(-5410 2610);
DISPLAY 0.617021 (-5410 2610);
PAINT ORANGE (-5410 2610);
FORCEPROP 2 LASTPIN (-5400 2550) $PN H1
J 2
(-5410 2560);
DISPLAY 0.617021 (-5410 2560);
PAINT ORANGE (-5410 2560);
FORCEPROP 2 LASTPIN (-5400 2500) $PN H83
J 2
(-5410 2510);
DISPLAY 0.617021 (-5410 2510);
PAINT ORANGE (-5410 2510);
FORCEPROP 2 LASTPIN (-5400 2450) $PN H85
J 2
(-5410 2460);
DISPLAY 0.617021 (-5410 2460);
PAINT ORANGE (-5410 2460);
FORCEPROP 2 LASTPIN (-5400 2400) $PN J46
J 2
(-5410 2410);
DISPLAY 0.617021 (-5410 2410);
PAINT ORANGE (-5410 2410);
FORCEPROP 2 LASTPIN (-5400 2350) $PN J62
J 2
(-5410 2360);
DISPLAY 0.617021 (-5410 2360);
PAINT ORANGE (-5410 2360);
FORCEPROP 2 LASTPIN (-5400 2300) $PN K61
J 2
(-5410 2310);
DISPLAY 0.617021 (-5410 2310);
PAINT ORANGE (-5410 2310);
FORCEPROP 2 LASTPIN (-5400 2250) $PN M63
J 2
(-5410 2260);
DISPLAY 0.617021 (-5410 2260);
PAINT ORANGE (-5410 2260);
FORCEPROP 2 LASTPIN (-5400 2200) $PN P65
J 2
(-5410 2210);
DISPLAY 0.617021 (-5410 2210);
PAINT ORANGE (-5410 2210);
FORCEPROP 2 LASTPIN (-5400 2150) $PN R62
J 2
(-5410 2160);
DISPLAY 0.617021 (-5410 2160);
PAINT ORANGE (-5410 2160);
FORCEPROP 2 LASTPIN (-5400 2100) $PN R66
J 2
(-5410 2110);
DISPLAY 0.617021 (-5410 2110);
PAINT ORANGE (-5410 2110);
FORCEPROP 2 LASTPIN (-5400 2050) $PN T67
J 2
(-5410 2060);
DISPLAY 0.617021 (-5410 2060);
PAINT ORANGE (-5410 2060);
FORCEPROP 2 LASTPIN (-5400 2000) $PN U66
J 2
(-5410 2010);
DISPLAY 0.617021 (-5410 2010);
PAINT ORANGE (-5410 2010);
FORCEPROP 2 LASTPIN (-5400 1950) $PN V65
J 2
(-5410 1960);
DISPLAY 0.617021 (-5410 1960);
PAINT ORANGE (-5410 1960);
FORCEPROP 2 LASTPIN (-5400 1850) $PN V67
J 2
(-5410 1860);
DISPLAY 0.617021 (-5410 1860);
PAINT ORANGE (-5410 1860);
FORCEPROP 2 LASTPIN (-5400 1800) $PN W66
J 2
(-5410 1810);
DISPLAY 0.617021 (-5410 1810);
PAINT ORANGE (-5410 1810);
FORCEPROP 2 LASTPIN (-5400 1750) $PN Y23
J 2
(-5410 1760);
DISPLAY 0.617021 (-5410 1760);
PAINT ORANGE (-5410 1760);
FORCEPROP 2 LASTPIN (-5400 1700) $PN Y65
J 2
(-5410 1710);
DISPLAY 0.617021 (-5410 1710);
PAINT ORANGE (-5410 1710);
FORCEPROP 2 LASTPIN (-5400 1500) $PN AD47
J 2
(-5410 1510);
DISPLAY 0.617021 (-5410 1510);
PAINT ORANGE (-5410 1510);
FORCEPROP 2 LASTPIN (-5400 1450) $PN AD49
J 2
(-5410 1460);
DISPLAY 0.617021 (-5410 1460);
PAINT ORANGE (-5410 1460);
FORCEPROP 2 LASTPIN (-5400 1400) $PN AD51
J 2
(-5410 1410);
DISPLAY 0.617021 (-5410 1410);
PAINT ORANGE (-5410 1410);
FORCEPROP 2 LASTPIN (-5400 1350) $PN AE46
J 2
(-5410 1360);
DISPLAY 0.617021 (-5410 1360);
PAINT ORANGE (-5410 1360);
FORCEPROP 2 LASTPIN (-5400 1300) $PN AE48
J 2
(-5410 1310);
DISPLAY 0.617021 (-5410 1310);
PAINT ORANGE (-5410 1310);
FORCEPROP 2 LASTPIN (-5400 1250) $PN AE50
J 2
(-5410 1260);
DISPLAY 0.617021 (-5410 1260);
PAINT ORANGE (-5410 1260);
FORCEPROP 2 LASTPIN (-5400 1150) $PN AE52
J 2
(-5410 1160);
DISPLAY 0.617021 (-5410 1160);
PAINT ORANGE (-5410 1160);
FORCEPROP 2 LASTPIN (-5400 1100) $PN AE72
J 2
(-5410 1110);
DISPLAY 0.617021 (-5410 1110);
PAINT ORANGE (-5410 1110);
FORCEPROP 2 LASTPIN (-5400 1050) $PN AF19
J 2
(-5410 1060);
DISPLAY 0.617021 (-5410 1060);
PAINT ORANGE (-5410 1060);
FORCEPROP 2 LASTPIN (-5400 1000) $PN AF47
J 2
(-5410 1010);
DISPLAY 0.617021 (-5410 1010);
PAINT ORANGE (-5410 1010);
FORCEPROP 2 LASTPIN (-5400 950) $PN AF49
J 2
(-5410 960);
DISPLAY 0.617021 (-5410 960);
PAINT ORANGE (-5410 960);
FORCEPROP 2 LASTPIN (-5400 900) $PN AF51
J 2
(-5410 910);
DISPLAY 0.617021 (-5410 910);
PAINT ORANGE (-5410 910);
FORCEPROP 2 LASTPIN (-5400 750) $PN AF53
J 2
(-5410 760);
DISPLAY 0.617021 (-5410 760);
PAINT ORANGE (-5410 760);
FORCEPROP 2 LASTPIN (-2900 4350) $PN AF71
J 0
(-2890 4360);
DISPLAY 0.617021 (-2890 4360);
PAINT ORANGE (-2890 4360);
FORCEPROP 2 LASTPIN (-2900 4300) $PN AG20
J 0
(-2890 4310);
DISPLAY 0.617021 (-2890 4310);
PAINT ORANGE (-2890 4310);
FORCEPROP 2 LASTPIN (-2900 4250) $PN AG48
J 0
(-2890 4260);
DISPLAY 0.617021 (-2890 4260);
PAINT ORANGE (-2890 4260);
FORCEPROP 2 LASTPIN (-2900 4200) $PN AG50
J 0
(-2890 4210);
DISPLAY 0.617021 (-2890 4210);
PAINT ORANGE (-2890 4210);
FORCEPROP 2 LASTPIN (-2900 4150) $PN AG52
J 0
(-2890 4160);
DISPLAY 0.617021 (-2890 4160);
PAINT ORANGE (-2890 4160);
FORCEPROP 2 LASTPIN (-2900 4100) $PN AG54
J 0
(-2890 4110);
DISPLAY 0.617021 (-2890 4110);
PAINT ORANGE (-2890 4110);
FORCEPROP 2 LASTPIN (-2900 4050) $PN AG56
J 0
(-2890 4060);
DISPLAY 0.617021 (-2890 4060);
PAINT ORANGE (-2890 4060);
FORCEPROP 2 LASTPIN (-2900 3950) $PN AG72
J 0
(-2890 3960);
DISPLAY 0.617021 (-2890 3960);
PAINT ORANGE (-2890 3960);
FORCEPROP 2 LASTPIN (-2900 3900) $PN AH15
J 0
(-2890 3910);
DISPLAY 0.617021 (-2890 3910);
PAINT ORANGE (-2890 3910);
FORCEPROP 2 LASTPIN (-2900 3850) $PN AH19
J 0
(-2890 3860);
DISPLAY 0.617021 (-2890 3860);
PAINT ORANGE (-2890 3860);
FORCEPROP 2 LASTPIN (-2900 3800) $PN AH55
J 0
(-2890 3810);
DISPLAY 0.617021 (-2890 3810);
PAINT ORANGE (-2890 3810);
FORCEPROP 2 LASTPIN (-2900 3750) $PN AH57
J 0
(-2890 3760);
DISPLAY 0.617021 (-2890 3760);
PAINT ORANGE (-2890 3760);
FORCEPROP 2 LASTPIN (-2900 3700) $PN AH71
J 0
(-2890 3710);
DISPLAY 0.617021 (-2890 3710);
PAINT ORANGE (-2890 3710);
FORCEPROP 2 LASTPIN (-2900 3650) $PN AH73
J 0
(-2890 3660);
DISPLAY 0.617021 (-2890 3660);
PAINT ORANGE (-2890 3660);
FORCEPROP 2 LASTPIN (-2900 3500) $PN AJ56
J 0
(-2890 3510);
DISPLAY 0.617021 (-2890 3510);
PAINT ORANGE (-2890 3510);
FORCEPROP 2 LASTPIN (-2900 3450) $PN AJ58
J 0
(-2890 3460);
DISPLAY 0.617021 (-2890 3460);
PAINT ORANGE (-2890 3460);
FORCEPROP 2 LASTPIN (-2900 3400) $PN AJ60
J 0
(-2890 3410);
DISPLAY 0.617021 (-2890 3410);
PAINT ORANGE (-2890 3410);
FORCEPROP 2 LASTPIN (-2900 3350) $PN AJ62
J 0
(-2890 3360);
DISPLAY 0.617021 (-2890 3360);
PAINT ORANGE (-2890 3360);
FORCEPROP 2 LASTPIN (-2900 3300) $PN AJ70
J 0
(-2890 3310);
DISPLAY 0.617021 (-2890 3310);
PAINT ORANGE (-2890 3310);
FORCEPROP 2 LASTPIN (-2900 3250) $PN AK21
J 0
(-2890 3260);
DISPLAY 0.617021 (-2890 3260);
PAINT ORANGE (-2890 3260);
FORCEPROP 2 LASTPIN (-2900 2700) $PN AK27
J 0
(-2890 2710);
DISPLAY 0.617021 (-2890 2710);
PAINT ORANGE (-2890 2710);
FORCEPROP 2 LASTPIN (-2900 2600) $PN AK57
J 0
(-2890 2610);
DISPLAY 0.617021 (-2890 2610);
PAINT ORANGE (-2890 2610);
FORCEPROP 2 LASTPIN (-2900 2550) $PN AK59
J 0
(-2890 2560);
DISPLAY 0.617021 (-2890 2560);
PAINT ORANGE (-2890 2560);
FORCEPROP 2 LASTPIN (-2900 2500) $PN AK61
J 0
(-2890 2510);
DISPLAY 0.617021 (-2890 2510);
PAINT ORANGE (-2890 2510);
FORCEPROP 2 LASTPIN (-2900 2250) $PN AK69
J 0
(-2890 2260);
DISPLAY 0.617021 (-2890 2260);
PAINT ORANGE (-2890 2260);
FORCEPROP 2 LASTPIN (-2900 2200) $PN AL20
J 0
(-2890 2210);
DISPLAY 0.617021 (-2890 2210);
PAINT ORANGE (-2890 2210);
FORCEPROP 2 LASTPIN (-2900 2000) $PN AL22
J 0
(-2890 2010);
DISPLAY 0.617021 (-2890 2010);
PAINT ORANGE (-2890 2010);
FORCEPROP 2 LASTPIN (-2900 1850) $PN AL26
J 0
(-2890 1860);
DISPLAY 0.617021 (-2890 1860);
PAINT ORANGE (-2890 1860);
FORCEPROP 2 LASTPIN (-2900 1800) $PN AL58
J 0
(-2890 1810);
DISPLAY 0.617021 (-2890 1810);
PAINT ORANGE (-2890 1810);
FORCEPROP 2 LASTPIN (-2900 1750) $PN AL60
J 0
(-2890 1760);
DISPLAY 0.617021 (-2890 1760);
PAINT ORANGE (-2890 1760);
FORCEPROP 2 LASTPIN (-2900 1700) $PN AL62
J 0
(-2890 1710);
DISPLAY 0.617021 (-2890 1710);
PAINT ORANGE (-2890 1710);
FORCEPROP 2 LASTPIN (-2900 1650) $PN AM21
J 0
(-2890 1660);
DISPLAY 0.617021 (-2890 1660);
PAINT ORANGE (-2890 1660);
FORCEPROP 2 LASTPIN (-2900 1550) $PN AM23
J 0
(-2890 1560);
DISPLAY 0.617021 (-2890 1560);
PAINT ORANGE (-2890 1560);
FORCEPROP 2 LASTPIN (-2900 1500) $PN AM25
J 0
(-2890 1510);
DISPLAY 0.617021 (-2890 1510);
PAINT ORANGE (-2890 1510);
FORCEPROP 2 LASTPIN (-2900 1450) $PN AM27
J 0
(-2890 1460);
DISPLAY 0.617021 (-2890 1460);
PAINT ORANGE (-2890 1460);
FORCEPROP 2 LASTPIN (-2900 1400) $PN AM59
J 0
(-2890 1410);
DISPLAY 0.617021 (-2890 1410);
PAINT ORANGE (-2890 1410);
FORCEPROP 2 LASTPIN (-2900 1350) $PN AM61
J 0
(-2890 1360);
DISPLAY 0.617021 (-2890 1360);
PAINT ORANGE (-2890 1360);
FORCEPROP 2 LASTPIN (-2900 1300) $PN AN18
J 0
(-2890 1310);
DISPLAY 0.617021 (-2890 1310);
PAINT ORANGE (-2890 1310);
FORCEPROP 2 LASTPIN (-2900 1200) $PN AN22
J 0
(-2890 1210);
DISPLAY 0.617021 (-2890 1210);
PAINT ORANGE (-2890 1210);
FORCEPROP 2 LASTPIN (-2900 1150) $PN AN24
J 0
(-2890 1160);
DISPLAY 0.617021 (-2890 1160);
PAINT ORANGE (-2890 1160);
FORCEPROP 2 LASTPIN (-2900 1100) $PN AN26
J 0
(-2890 1110);
DISPLAY 0.617021 (-2890 1110);
PAINT ORANGE (-2890 1110);
FORCEPROP 2 LASTPIN (-2900 1050) $PN AN60
J 0
(-2890 1060);
DISPLAY 0.617021 (-2890 1060);
PAINT ORANGE (-2890 1060);
FORCEPROP 2 LASTPIN (-2900 1000) $PN AN62
J 0
(-2890 1010);
DISPLAY 0.617021 (-2890 1010);
PAINT ORANGE (-2890 1010);
FORCEPROP 2 LASTPIN (-2900 950) $PN AP23
J 0
(-2890 960);
DISPLAY 0.617021 (-2890 960);
PAINT ORANGE (-2890 960);
FORCEPROP 2 LASTPIN (-2900 900) $PN AP25
J 0
(-2890 910);
DISPLAY 0.617021 (-2890 910);
PAINT ORANGE (-2890 910);
FORCEPROP 2 LASTPIN (-2900 850) $PN AP27
J 0
(-2890 860);
DISPLAY 0.617021 (-2890 860);
PAINT ORANGE (-2890 860);
FORCEPROP 2 LASTPIN (-2900 800) $PN AP61
J 0
(-2890 810);
DISPLAY 0.617021 (-2890 810);
PAINT ORANGE (-2890 810);
FORCEPROP 2 LASTPIN (-2900 2850) $PN AP17
J 0
(-2890 2860);
DISPLAY 0.617021 (-2890 2860);
PAINT ORANGE (-2890 2860);
FORCEPROP 2 LASTPIN (-2900 2650) $PN AU14
J 0
(-2890 2660);
DISPLAY 0.617021 (-2890 2660);
PAINT ORANGE (-2890 2660);
FORCEPROP 2 LASTPIN (-2900 2050) $PN AW12
J 0
(-2890 2060);
DISPLAY 0.617021 (-2890 2060);
PAINT ORANGE (-2890 2060);
FORCEPROP 2 LASTPIN (-2900 2450) $PN AV21
J 0
(-2890 2460);
DISPLAY 0.617021 (-2890 2460);
PAINT ORANGE (-2890 2460);
FORCEPROP 2 LASTPIN (-2900 3550) $PN AJ20
J 0
(-2890 3560);
DISPLAY 0.617021 (-2890 3560);
PAINT ORANGE (-2890 3560);
FORCEPROP 1 LAST PACK_TYPE BGA1
J 0
(-5350 4650);
PAINT SKYBLUE (-5350 4650);
DISPLAY INVISIBLE (-5350 4650);
FORCEPROP 2 LAST CDS_LIB chpset_lib
J 0
(-4150 2550);
PAINT ORANGE (-4150 2550);
DISPLAY INVISIBLE (-4150 2550);
FORCEPROP 2 LAST SEC_TYPE BGA1
J 0
(-5350 4650);
DISPLAY 1.021277 (-5350 4650);
PAINT ORANGE (-5350 4650);
DISPLAY INVISIBLE (-5350 4650);
FORCEPROP 2 LAST SEC 2
J 0
(-5350 4650);
DISPLAY 0.680851 (-5350 4650);
PAINT MONO (-5350 4650);
DISPLAY INVISIBLE (-5350 4650);
FORCEPROP 2 LAST CDS_LOCATION U5D1
J 0
(-5350 4600);
DISPLAY 0.617021 (-5350 4600);
PAINT AQUA (-5350 4600);
DISPLAY INVISIBLE (-5350 4600);
FORCEPROP 1 LAST PATH I204
J 0
(-4150 4550);
PAINT GREEN (-4150 4550);
DISPLAY INVISIBLE (-4150 4550);
FORCEPROP 0 LAST ROOM CPU0
J 0
(-5350 4700);
DISPLAY 1.021277 (-5350 4700);
PAINT ORANGE (-5350 4700);
DISPLAY INVISIBLE (-5350 4700);
FORCEADD OFFPAGE..2
R 2
(-7150 1750);
FORCEPROP 2 LAST $XR0 133 
J 0
(-7405 1750);
DISPLAY 0.638298 (-7405 1750);
PAINT MONO (-7405 1750);
FORCEPROP 2 LAST $XR1 118 
J 0
(-7525 1750);
DISPLAY 0.638298 (-7525 1750);
PAINT MONO (-7525 1750);
FORCEPROP 2 LAST $XR2 120 
J 0
(-7645 1750);
DISPLAY 0.638298 (-7645 1750);
PAINT MONO (-7645 1750);
FORCEPROP 2 LAST $XR3 145 
J 0
(-7765 1750);
DISPLAY 0.638298 (-7765 1750);
PAINT MONO (-7765 1750);
FORCEPROP 2 LAST CDS_LIB mstr_standard
J 2
(-7150 1750);
PAINT ORANGE (-7150 1750);
DISPLAY INVISIBLE (-7150 1750);
FORCEPROP 1 LAST OFFPAGE TRUE
J 2
(-7475 1625);
DISPLAY 0.489362 (-7475 1625);
PAINT GREEN (-7475 1625);
DISPLAY INVISIBLE (-7475 1625);
FORCEPROP 1 LAST COMMENT_BODY TRUE
J 2
(-7105 1655);
DISPLAY 0.936170 (-7105 1655);
PAINT PEACH (-7105 1655);
DISPLAY INVISIBLE (-7105 1655);
FORCEPROP 2 LAST PATH I205
J 2
(-7325 1825);
DISPLAY 1.021277 (-7325 1825);
PAINT ORANGE (-7325 1825);
DISPLAY INVISIBLE (-7325 1825);
FORCEADD OFFPAGE..4
(-1625 3250);
FORCEPROP 2 LAST $XR0 194 
J 0
(-1439 3250);
DISPLAY 0.638298 (-1439 3250);
PAINT MONO (-1439 3250);
FORCEPROP 2 LAST CDS_LIB mstr_standard
J 0
(-1625 3250);
PAINT ORANGE (-1625 3250);
DISPLAY INVISIBLE (-1625 3250);
FORCEPROP 1 LAST OFFPAGE TRUE
J 0
(-1300 3125);
DISPLAY 0.680851 (-1300 3125);
PAINT GREEN (-1300 3125);
DISPLAY INVISIBLE (-1300 3125);
FORCEPROP 1 LAST COMMENT_BODY TRUE
J 0
(-1650 3150);
DISPLAY 0.680851 (-1650 3150);
PAINT PEACH (-1650 3150);
DISPLAY INVISIBLE (-1650 3150);
FORCEPROP 2 LAST PATH I206
J 0
(-1450 3325);
DISPLAY 1.021277 (-1450 3325);
PAINT ORANGE (-1450 3325);
DISPLAY INVISIBLE (-1450 3325);
FORCEADD OFFPAGE..4
(-1600 2200);
FORCEPROP 2 LAST $XR0 194 
J 0
(-1414 2200);
DISPLAY 0.638298 (-1414 2200);
PAINT MONO (-1414 2200);
FORCEPROP 2 LAST CDS_LIB mstr_standard
J 0
(-1600 2200);
PAINT ORANGE (-1600 2200);
DISPLAY INVISIBLE (-1600 2200);
FORCEPROP 1 LAST OFFPAGE TRUE
J 0
(-1275 2075);
DISPLAY 0.680851 (-1275 2075);
PAINT GREEN (-1275 2075);
DISPLAY INVISIBLE (-1275 2075);
FORCEPROP 1 LAST COMMENT_BODY TRUE
J 0
(-1625 2100);
DISPLAY 0.680851 (-1625 2100);
PAINT PEACH (-1625 2100);
DISPLAY INVISIBLE (-1625 2100);
FORCEPROP 2 LAST PATH I207
J 0
(-1425 2275);
DISPLAY 1.021277 (-1425 2275);
PAINT ORANGE (-1425 2275);
DISPLAY INVISIBLE (-1425 2275);
FORCEADD PRELIM..10
(-3940 2615);
PAINT GRAY (-3940 2615);
FORCEPROP 2 LAST CDS_LIB mstr_misc
J 0
(-3940 2615);
PAINT ORANGE (-3940 2615);
DISPLAY INVISIBLE (-3940 2615);
FORCEPROP 1 LAST COMMENT_BODY TRUE
J 0
(-3940 2615);
PAINT ORANGE (-3940 2615);
DISPLAY INVISIBLE (-3940 2615);
FORCEADD DESIGN_NOTE..1
(-700 1725);
FORCEPROP 0 LAST L1 CLKS USED FOR DEBUG ONLY
J 0
(-875 1600);
DISPLAY 0.808511 (-875 1600);
PAINT ORANGE (-875 1600);
FORCEPROP 2 LAST CDS_LIB mstr_symbols
J 0
(-700 1725);
PAINT ORANGE (-700 1725);
DISPLAY INVISIBLE (-700 1725);
FORCEPROP 1 LAST COMMENT_BODY TRUE
J 0
(-675 1825);
DISPLAY 0.978723 (-675 1825);
PAINT ORANGE (-675 1825);
DISPLAY INVISIBLE (-675 1825);
FORCEADD DESIGN_NOTE..1
(-4900 475);
FORCEPROP 0 LAST L1 CPU SYMBOLS 1-30 ARE PRELIMINARY AND SUBJECT TO CHANGE
J 0
(-5100 350);
DISPLAY 1.021277 (-5100 350);
PAINT ORANGE (-5100 350);
FORCEPROP 2 LAST CDS_LIB mstr_symbols
J 0
(-4900 475);
PAINT ORANGE (-4900 475);
DISPLAY INVISIBLE (-4900 475);
FORCEPROP 1 LAST COMMENT_BODY TRUE
J 0
(-4875 575);
DISPLAY 0.978723 (-4875 575);
PAINT ORANGE (-4875 575);
DISPLAY INVISIBLE (-4875 575);
FORCEADD INTEL_CORP_BPAGE..1
(0 0);
FORCEPROP 1 LAST CDS_CON_LAST_MODIFIED Tue Dec 01 11:51:15 2015
J 0
(-1425 325);
DISPLAY 1.340426 (-1425 325);
PAINT GREEN (-1425 325);
DISPLAY INVISIBLE (-1425 325);
FORCEPROP 1 LAST CUSTOM_TXT_CDS <CURRENT_DESIGN_SHEET> OF <TOTAL_DESIGN_SHEETS>
J 0
(-500 25);
PAINT GREEN (-500 25);
FORCEPROP 1 LAST CUSTOM_TXT_CDS <CON_LAST_MODIFIED>
J 0
(-1925 350);
PAINT GREEN (-1925 350);
FORCEPROP 2 LAST CUSTOM_TXT_CDS <XR_PAGE_TITLE>
J 0
(-7890 5250);
DISPLAY 0.638298 (-7890 5250);
PAINT PINK (-7890 5250);
DISPLAY INVISIBLE (-7890 5250);
FORCEPROP 1 LAST SCH_ADDRESS3 Santa Clara, CA 95052-8119
J 0
(-3975 25);
DISPLAY 0.617021 (-3975 25);
PAINT GREEN (-3975 25);
FORCEPROP 1 LAST SCH_ADDRESS2 P.O. BOX 58119
J 0
(-3975 75);
DISPLAY 0.617021 (-3975 75);
PAINT GREEN (-3975 75);
FORCEPROP 1 LAST SCH_ADDRESS1 2200 Mission College Blvd.
J 0
(-3975 125);
DISPLAY 0.617021 (-3975 125);
PAINT GREEN (-3975 125);
FORCEPROP 1 LAST SCH_TITLE SKYLAKE - SKT0 - 2 OF 21
J 0
(-7950 50);
DISPLAY 1.212766 (-7950 50);
PAINT GREEN (-7950 50);
FORCEPROP 1 LAST SCH_NUMBER H4694802
J 0
(-1300 150);
DISPLAY 1.212766 (-1300 150);
PAINT YELLOW (-1300 150);
FORCEPROP 1 LAST SCH_DEPT BESD
J 1
(-4450 100);
DISPLAY 1.212766 (-4450 100);
PAINT YELLOW (-4450 100);
FORCEPROP 1 LAST SCH_REV 2.420
J 0
(-250 150);
DISPLAY 0.978723 (-250 150);
PAINT YELLOW (-250 150);
FORCEPROP 2 LAST PAGE_BORDER TRUE
J 0
(-7890 5250);
DISPLAY 0.851064 (-7890 5250);
PAINT PINK (-7890 5250);
DISPLAY INVISIBLE (-7890 5250);
FORCEPROP 2 LAST CDS_LIB mstr_symbols
J 0
(0 0);
PAINT ORANGE (0 0);
DISPLAY INVISIBLE (0 0);
FORCEPROP 1 LAST COMMENT_BODY TRUE
J 0
(12 12);
DISPLAY 0.638298 (12 12);
PAINT GREEN (12 12);
DISPLAY INVISIBLE (12 12);
FORCEPROP 2 LAST CDS_XR_PAGE_TITLE CR-22 : @BASEBOARD_FAB2_LIB.BASEBOARD_FAB2(SCH_1):PAGE22
J 0
(-7890 5250);
DISPLAY 0.638298 (-7890 5250);
PAINT PINK (-7890 5250);
DISPLAY INVISIBLE (-7890 5250);
WIRE 16 -1 (-575 2675)(-575 2550);
WIRE 16 -1 (-575 2550)(-300 2550);
WIRE 16 -1 (-300 2675)(-300 2550);
WIRE 16 -1 (-300 2550)(-300 2500);
WIRE 16 -1 (-2900 1300)(-2750 1300);
WIRE 16 -1 (-2750 1300)(-2750 1200);
WIRE 16 -1 (-2900 1200)(-2750 1200);
WIRE 16 -1 (-2750 1200)(-2750 1150);
WIRE 16 -1 (-2900 1150)(-2750 1150);
WIRE 16 -1 (-2750 1150)(-2750 1100);
WIRE 16 -1 (-2900 1100)(-2750 1100);
WIRE 16 -1 (-2750 1100)(-1100 1100);
WIRE 16 -1 (-1100 900)(-1100 1100);
WIRE 16 -1 (-1100 1100)(-1100 1500);
WIRE 16 -1 (-2900 1500)(-1100 1500);
WIRE 16 -1 (-1100 1500)(-1100 1650);
WIRE 16 -1 (-2750 900)(-1100 900);
WIRE 16 -1 (-2750 950)(-2750 900);
WIRE 16 -1 (-2900 900)(-2750 900);
WIRE 16 -1 (-2900 1650)(-1100 1650);
WIRE 16 -1 (-1100 2275)(-1100 1650);
WIRE 16 -1 (-2900 950)(-2750 950);
WIRE 16 -1 (-5400 3850)(-5575 3850);
WIRE 16 -1 (-5575 3850)(-5575 3900);
WIRE 16 -1 (-5400 3900)(-5575 3900);
WIRE 16 -1 (-5575 3900)(-5575 3950);
WIRE 16 -1 (-5400 3950)(-5575 3950);
WIRE 16 -1 (-5575 3950)(-7300 3950);
WIRE 16 -1 (-7300 3950)(-7300 4250);
WIRE 16 -1 (-5575 4250)(-7300 4250);
WIRE 16 -1 (-7300 4250)(-7300 4425);
WIRE 16 -1 (-5575 4200)(-5575 4250);
WIRE 16 -1 (-5400 4250)(-5575 4250);
WIRE 16 -1 (-5400 4200)(-5575 4200);
WIRE 16 -1 (-5400 2300)(-6450 2300);
FORCEPROP 2 LAST SIG_NAME TP_CPU0_RSVD_267
J 0
(-6425 2310);
DISPLAY 0.617021 (-6425 2310);
PAINT ORANGE (-6425 2310);
FORCEPROP 2 LASTPROP $XRERR UNIQUE?
J 0
(-6690 2300);
DISPLAY 0.638298 (-6690 2300);
PAINT MONO (-6690 2300);
DISPLAY INVISIBLE (-6690 2300);
WIRE 16 -1 (-5400 3350)(-6450 3350);
FORCEPROP 2 LAST SIG_NAME TP_CPU0_RSVD_285
J 0
(-6425 3360);
DISPLAY 0.617021 (-6425 3360);
PAINT ORANGE (-6425 3360);
FORCEPROP 2 LASTPROP $XRERR UNIQUE?
J 0
(-6690 3350);
DISPLAY 0.638298 (-6690 3350);
PAINT MONO (-6690 3350);
DISPLAY INVISIBLE (-6690 3350);
WIRE 16 -1 (-5400 3200)(-6450 3200);
FORCEPROP 2 LAST SIG_NAME TP_CPU0_RSVD_282
J 0
(-6425 3210);
DISPLAY 0.617021 (-6425 3210);
PAINT ORANGE (-6425 3210);
FORCEPROP 2 LASTPROP $XRERR UNIQUE?
J 0
(-6690 3200);
DISPLAY 0.638298 (-6690 3200);
PAINT MONO (-6690 3200);
DISPLAY INVISIBLE (-6690 3200);
WIRE 16 -1 (-6450 1950)(-5400 1950);
FORCEPROP 2 LAST SIG_NAME TP_CPU0_RSVD_260
J 0
(-6425 1960);
DISPLAY 0.617021 (-6425 1960);
PAINT ORANGE (-6425 1960);
FORCEPROP 2 LASTPROP $XRERR UNIQUE?
J 0
(-6690 1950);
DISPLAY 0.638298 (-6690 1950);
PAINT MONO (-6690 1950);
DISPLAY INVISIBLE (-6690 1950);
WIRE 16 -1 (-5400 2450)(-6450 2450);
FORCEPROP 2 LAST SIG_NAME TP_CPU0_RSVD_270
J 0
(-6425 2460);
DISPLAY 0.617021 (-6425 2460);
PAINT ORANGE (-6425 2460);
FORCEPROP 2 LASTPROP $XRERR UNIQUE?
J 0
(-6690 2450);
DISPLAY 0.638298 (-6690 2450);
PAINT MONO (-6690 2450);
DISPLAY INVISIBLE (-6690 2450);
WIRE 16 -1 (-5400 2400)(-6450 2400);
FORCEPROP 2 LAST SIG_NAME TP_CPU0_RSVD_269
J 0
(-6425 2410);
DISPLAY 0.617021 (-6425 2410);
PAINT ORANGE (-6425 2410);
FORCEPROP 2 LASTPROP $XRERR UNIQUE?
J 0
(-6690 2400);
DISPLAY 0.638298 (-6690 2400);
PAINT MONO (-6690 2400);
DISPLAY INVISIBLE (-6690 2400);
WIRE 16 -1 (-5400 2100)(-6450 2100);
FORCEPROP 2 LAST SIG_NAME TP_CPU0_RSVD_263
J 0
(-6425 2110);
DISPLAY 0.617021 (-6425 2110);
PAINT ORANGE (-6425 2110);
FORCEPROP 2 LASTPROP $XRERR UNIQUE?
J 0
(-6690 2100);
DISPLAY 0.638298 (-6690 2100);
PAINT MONO (-6690 2100);
DISPLAY INVISIBLE (-6690 2100);
WIRE 16 -1 (-5400 2500)(-6450 2500);
FORCEPROP 2 LAST SIG_NAME TP_CPU0_RSVD_271
J 0
(-6425 2510);
DISPLAY 0.617021 (-6425 2510);
PAINT ORANGE (-6425 2510);
FORCEPROP 2 LASTPROP $XRERR UNIQUE?
J 0
(-6690 2500);
DISPLAY 0.638298 (-6690 2500);
PAINT MONO (-6690 2500);
DISPLAY INVISIBLE (-6690 2500);
WIRE 16 -1 (-5400 2600)(-6450 2600);
FORCEPROP 2 LAST SIG_NAME TP_CPU0_RSVD_273
J 0
(-6425 2610);
DISPLAY 0.617021 (-6425 2610);
PAINT ORANGE (-6425 2610);
FORCEPROP 2 LASTPROP $XRERR UNIQUE?
J 0
(-6690 2600);
DISPLAY 0.638298 (-6690 2600);
PAINT MONO (-6690 2600);
DISPLAY INVISIBLE (-6690 2600);
WIRE 16 -1 (-5400 2350)(-6450 2350);
FORCEPROP 2 LAST SIG_NAME TP_CPU0_RSVD_268
J 0
(-6425 2360);
DISPLAY 0.617021 (-6425 2360);
PAINT ORANGE (-6425 2360);
FORCEPROP 2 LASTPROP $XRERR UNIQUE?
J 0
(-6690 2350);
DISPLAY 0.638298 (-6690 2350);
PAINT MONO (-6690 2350);
DISPLAY INVISIBLE (-6690 2350);
WIRE 16 -1 (-5400 3250)(-6475 3250);
FORCEPROP 2 LAST SIG_NAME TP_CPU0_RSVD_283
J 0
(-6425 3260);
DISPLAY 0.617021 (-6425 3260);
PAINT ORANGE (-6425 3260);
FORCEPROP 2 LASTPROP $XRERR UNIQUE?
J 0
(-6715 3250);
DISPLAY 0.638298 (-6715 3250);
PAINT MONO (-6715 3250);
DISPLAY INVISIBLE (-6715 3250);
WIRE 16 -1 (-5400 3300)(-6450 3300);
FORCEPROP 2 LAST SIG_NAME TP_CPU0_RSVD_284
J 0
(-6425 3310);
DISPLAY 0.617021 (-6425 3310);
PAINT ORANGE (-6425 3310);
FORCEPROP 2 LASTPROP $XRERR UNIQUE?
J 0
(-6690 3300);
DISPLAY 0.638298 (-6690 3300);
PAINT MONO (-6690 3300);
DISPLAY INVISIBLE (-6690 3300);
WIRE 16 -1 (-5400 3400)(-6450 3400);
FORCEPROP 2 LAST SIG_NAME TP_CPU0_RSVD_286
J 0
(-6425 3410);
DISPLAY 0.617021 (-6425 3410);
PAINT ORANGE (-6425 3410);
FORCEPROP 2 LASTPROP $XRERR UNIQUE?
J 0
(-6690 3400);
DISPLAY 0.638298 (-6690 3400);
PAINT MONO (-6690 3400);
DISPLAY INVISIBLE (-6690 3400);
WIRE 16 -1 (-5400 3450)(-6450 3450);
FORCEPROP 2 LAST SIG_NAME TP_CPU0_RSVD_287
J 0
(-6425 3460);
DISPLAY 0.617021 (-6425 3460);
PAINT ORANGE (-6425 3460);
FORCEPROP 2 LASTPROP $XRERR UNIQUE?
J 0
(-6690 3450);
DISPLAY 0.638298 (-6690 3450);
PAINT MONO (-6690 3450);
DISPLAY INVISIBLE (-6690 3450);
WIRE 16 -1 (-5400 3500)(-6450 3500);
FORCEPROP 2 LAST SIG_NAME TP_CPU0_RSVD_288
J 0
(-6425 3510);
DISPLAY 0.617021 (-6425 3510);
PAINT ORANGE (-6425 3510);
FORCEPROP 2 LASTPROP $XRERR UNIQUE?
J 0
(-6690 3500);
DISPLAY 0.638298 (-6690 3500);
PAINT MONO (-6690 3500);
DISPLAY INVISIBLE (-6690 3500);
WIRE 16 -1 (-5400 3550)(-6450 3550);
FORCEPROP 2 LAST SIG_NAME TP_CPU0_RSVD_289
J 0
(-6425 3560);
DISPLAY 0.617021 (-6425 3560);
PAINT ORANGE (-6425 3560);
FORCEPROP 2 LASTPROP $XRERR UNIQUE?
J 0
(-6690 3550);
DISPLAY 0.638298 (-6690 3550);
PAINT MONO (-6690 3550);
DISPLAY INVISIBLE (-6690 3550);
WIRE 16 -1 (-5400 3650)(-6450 3650);
FORCEPROP 2 LAST SIG_NAME TP_CPU0_RSVD_290
J 0
(-6425 3660);
DISPLAY 0.617021 (-6425 3660);
PAINT ORANGE (-6425 3660);
FORCEPROP 2 LASTPROP $XRERR UNIQUE?
J 0
(-6690 3650);
DISPLAY 0.638298 (-6690 3650);
PAINT MONO (-6690 3650);
DISPLAY INVISIBLE (-6690 3650);
WIRE 16 -1 (-5400 3700)(-6450 3700);
FORCEPROP 2 LAST SIG_NAME TP_CPU0_RSVD_291
J 0
(-6425 3710);
DISPLAY 0.617021 (-6425 3710);
PAINT ORANGE (-6425 3710);
FORCEPROP 2 LASTPROP $XRERR UNIQUE?
J 0
(-6690 3700);
DISPLAY 0.638298 (-6690 3700);
PAINT MONO (-6690 3700);
DISPLAY INVISIBLE (-6690 3700);
WIRE 16 -1 (-5400 3750)(-6450 3750);
FORCEPROP 2 LAST SIG_NAME TP_CPU0_RSVD_292
J 0
(-6425 3760);
DISPLAY 0.617021 (-6425 3760);
PAINT ORANGE (-6425 3760);
FORCEPROP 2 LASTPROP $XRERR UNIQUE?
J 0
(-6690 3750);
DISPLAY 0.638298 (-6690 3750);
PAINT MONO (-6690 3750);
DISPLAY INVISIBLE (-6690 3750);
WIRE 16 -1 (-5400 3800)(-6450 3800);
FORCEPROP 2 LAST SIG_NAME TP_CPU0_RSVD_293
J 0
(-6425 3810);
DISPLAY 0.617021 (-6425 3810);
PAINT ORANGE (-6425 3810);
FORCEPROP 2 LASTPROP $XRERR UNIQUE?
J 0
(-6690 3800);
DISPLAY 0.638298 (-6690 3800);
PAINT MONO (-6690 3800);
DISPLAY INVISIBLE (-6690 3800);
WIRE 16 -1 (-5400 4050)(-6450 4050);
FORCEPROP 2 LAST SIG_NAME TP_CPU0_RSVD_298
J 0
(-6425 4060);
DISPLAY 0.617021 (-6425 4060);
PAINT ORANGE (-6425 4060);
FORCEPROP 2 LASTPROP $XRERR UNIQUE?
J 0
(-6690 4050);
DISPLAY 0.638298 (-6690 4050);
PAINT MONO (-6690 4050);
DISPLAY INVISIBLE (-6690 4050);
WIRE 16 -1 (-5400 2700)(-6475 2700);
FORCEPROP 2 LAST SIG_NAME TP_CPU0_RSVD_275
J 0
(-6425 2710);
DISPLAY 0.617021 (-6425 2710);
PAINT ORANGE (-6425 2710);
FORCEPROP 2 LASTPROP $XRERR UNIQUE?
J 0
(-6715 2700);
DISPLAY 0.638298 (-6715 2700);
PAINT MONO (-6715 2700);
DISPLAY INVISIBLE (-6715 2700);
WIRE 16 -1 (-5400 2650)(-6450 2650);
FORCEPROP 2 LAST SIG_NAME TP_CPU0_RSVD_274
J 0
(-6425 2660);
DISPLAY 0.617021 (-6425 2660);
PAINT ORANGE (-6425 2660);
FORCEPROP 2 LASTPROP $XRERR UNIQUE?
J 0
(-6690 2650);
DISPLAY 0.638298 (-6690 2650);
PAINT MONO (-6690 2650);
DISPLAY INVISIBLE (-6690 2650);
WIRE 16 -1 (-5400 2550)(-6450 2550);
FORCEPROP 2 LAST SIG_NAME TP_CPU0_RSVD_272
J 0
(-6425 2560);
DISPLAY 0.617021 (-6425 2560);
PAINT ORANGE (-6425 2560);
FORCEPROP 2 LASTPROP $XRERR UNIQUE?
J 0
(-6690 2550);
DISPLAY 0.638298 (-6690 2550);
PAINT MONO (-6690 2550);
DISPLAY INVISIBLE (-6690 2550);
WIRE 16 -1 (-5400 2800)(-6450 2800);
FORCEPROP 2 LAST SIG_NAME TP_CPU0_RSVD_276
J 0
(-6425 2810);
DISPLAY 0.617021 (-6425 2810);
PAINT ORANGE (-6425 2810);
FORCEPROP 2 LASTPROP $XRERR UNIQUE?
J 0
(-6690 2800);
DISPLAY 0.638298 (-6690 2800);
PAINT MONO (-6690 2800);
DISPLAY INVISIBLE (-6690 2800);
WIRE 16 -1 (-5400 2950)(-6450 2950);
FORCEPROP 2 LAST SIG_NAME TP_CPU0_RSVD_278
J 0
(-6425 2960);
DISPLAY 0.617021 (-6425 2960);
PAINT ORANGE (-6425 2960);
FORCEPROP 2 LASTPROP $XRERR UNIQUE?
J 0
(-6690 2950);
DISPLAY 0.638298 (-6690 2950);
PAINT MONO (-6690 2950);
DISPLAY INVISIBLE (-6690 2950);
WIRE 16 -1 (-5400 3050)(-6450 3050);
FORCEPROP 2 LAST SIG_NAME TP_CPU0_RSVD_280
J 0
(-6425 3060);
DISPLAY 0.617021 (-6425 3060);
PAINT ORANGE (-6425 3060);
FORCEPROP 2 LASTPROP $XRERR UNIQUE?
J 0
(-6690 3050);
DISPLAY 0.638298 (-6690 3050);
PAINT MONO (-6690 3050);
DISPLAY INVISIBLE (-6690 3050);
WIRE 16 -1 (-5400 2150)(-6450 2150);
FORCEPROP 2 LAST SIG_NAME TP_CPU0_RSVD_264
J 0
(-6425 2160);
DISPLAY 0.617021 (-6425 2160);
PAINT ORANGE (-6425 2160);
FORCEPROP 2 LASTPROP $XRERR UNIQUE?
J 0
(-6690 2150);
DISPLAY 0.638298 (-6690 2150);
PAINT MONO (-6690 2150);
DISPLAY INVISIBLE (-6690 2150);
WIRE 16 -1 (-5400 2050)(-6450 2050);
FORCEPROP 2 LAST SIG_NAME TP_CPU0_RSVD_262
J 0
(-6425 2060);
DISPLAY 0.617021 (-6425 2060);
PAINT ORANGE (-6425 2060);
FORCEPROP 2 LASTPROP $XRERR UNIQUE?
J 0
(-6690 2050);
DISPLAY 0.638298 (-6690 2050);
PAINT MONO (-6690 2050);
DISPLAY INVISIBLE (-6690 2050);
WIRE 16 -1 (-5400 2000)(-6450 2000);
FORCEPROP 2 LAST SIG_NAME TP_CPU0_RSVD_261
J 0
(-6425 2010);
DISPLAY 0.617021 (-6425 2010);
PAINT ORANGE (-6425 2010);
FORCEPROP 2 LASTPROP $XRERR UNIQUE?
J 0
(-6690 2000);
DISPLAY 0.638298 (-6690 2000);
PAINT MONO (-6690 2000);
DISPLAY INVISIBLE (-6690 2000);
WIRE 16 -1 (-5400 2850)(-6450 2850);
FORCEPROP 2 LAST SIG_NAME TP_CPU0_RSVD_277
J 0
(-6425 2860);
DISPLAY 0.617021 (-6425 2860);
PAINT ORANGE (-6425 2860);
FORCEPROP 2 LASTPROP $XRERR UNIQUE?
J 0
(-6690 2850);
DISPLAY 0.638298 (-6690 2850);
PAINT MONO (-6690 2850);
DISPLAY INVISIBLE (-6690 2850);
WIRE 16 -1 (-5400 3000)(-6450 3000);
FORCEPROP 2 LAST SIG_NAME TP_CPU0_RSVD_279
J 0
(-6425 3010);
DISPLAY 0.617021 (-6425 3010);
PAINT ORANGE (-6425 3010);
FORCEPROP 2 LASTPROP $XRERR UNIQUE?
J 0
(-6690 3000);
DISPLAY 0.638298 (-6690 3000);
PAINT MONO (-6690 3000);
DISPLAY INVISIBLE (-6690 3000);
WIRE 16 -1 (-5400 3100)(-6450 3100);
FORCEPROP 2 LAST SIG_NAME TP_CPU0_RSVD_281
J 0
(-6425 3110);
DISPLAY 0.617021 (-6425 3110);
PAINT ORANGE (-6425 3110);
FORCEPROP 2 LASTPROP $XRERR UNIQUE?
J 0
(-6690 3100);
DISPLAY 0.638298 (-6690 3100);
PAINT MONO (-6690 3100);
DISPLAY INVISIBLE (-6690 3100);
WIRE 16 -1 (-5400 1600)(-6450 1600);
FORCEPROP 2 LAST SIG_NAME TP_CPU0_RSVD_TEST_11
J 0
(-6425 1610);
DISPLAY 0.617021 (-6425 1610);
PAINT ORANGE (-6425 1610);
FORCEPROP 2 LASTPROP $XRERR UNIQUE?
J 0
(-6690 1600);
DISPLAY 0.638298 (-6690 1600);
PAINT MONO (-6690 1600);
DISPLAY INVISIBLE (-6690 1600);
WIRE 16 -1 (-5400 750)(-6450 750);
FORCEPROP 2 LAST SIG_NAME TP_CPU0_RSVD_242
J 0
(-6425 760);
DISPLAY 0.617021 (-6425 760);
PAINT ORANGE (-6425 760);
FORCEPROP 2 LASTPROP $XRERR UNIQUE?
J 0
(-6690 750);
DISPLAY 0.638298 (-6690 750);
PAINT MONO (-6690 750);
DISPLAY INVISIBLE (-6690 750);
WIRE 16 -1 (-5400 900)(-6450 900);
FORCEPROP 2 LAST SIG_NAME TP_CPU0_RSVD_243
J 0
(-6425 910);
DISPLAY 0.617021 (-6425 910);
PAINT ORANGE (-6425 910);
FORCEPROP 2 LASTPROP $XRERR UNIQUE?
J 0
(-6690 900);
DISPLAY 0.638298 (-6690 900);
PAINT MONO (-6690 900);
DISPLAY INVISIBLE (-6690 900);
WIRE 16 -1 (-5400 950)(-6450 950);
FORCEPROP 2 LAST SIG_NAME TP_CPU0_RSVD_244
J 0
(-6425 960);
DISPLAY 0.617021 (-6425 960);
PAINT ORANGE (-6425 960);
FORCEPROP 2 LASTPROP $XRERR UNIQUE?
J 0
(-6690 950);
DISPLAY 0.638298 (-6690 950);
PAINT MONO (-6690 950);
DISPLAY INVISIBLE (-6690 950);
WIRE 16 -1 (-5400 1000)(-6450 1000);
FORCEPROP 2 LAST SIG_NAME TP_CPU0_RSVD_245
J 0
(-6425 1010);
DISPLAY 0.617021 (-6425 1010);
PAINT ORANGE (-6425 1010);
FORCEPROP 2 LASTPROP $XRERR UNIQUE?
J 0
(-6690 1000);
DISPLAY 0.638298 (-6690 1000);
PAINT MONO (-6690 1000);
DISPLAY INVISIBLE (-6690 1000);
WIRE 16 -1 (-5400 1050)(-6450 1050);
FORCEPROP 2 LAST SIG_NAME TP_CPU0_RSVD_246
J 0
(-6425 1060);
DISPLAY 0.617021 (-6425 1060);
PAINT ORANGE (-6425 1060);
FORCEPROP 2 LASTPROP $XRERR UNIQUE?
J 0
(-6690 1050);
DISPLAY 0.638298 (-6690 1050);
PAINT MONO (-6690 1050);
DISPLAY INVISIBLE (-6690 1050);
WIRE 16 -1 (-5400 1100)(-6450 1100);
FORCEPROP 2 LAST SIG_NAME TP_CPU0_RSVD_247
J 0
(-6425 1110);
DISPLAY 0.617021 (-6425 1110);
PAINT ORANGE (-6425 1110);
FORCEPROP 2 LASTPROP $XRERR UNIQUE?
J 0
(-6690 1100);
DISPLAY 0.638298 (-6690 1100);
PAINT MONO (-6690 1100);
DISPLAY INVISIBLE (-6690 1100);
WIRE 16 -1 (-6450 1250)(-5400 1250);
FORCEPROP 2 LAST SIG_NAME TP_CPU0_RSVD_249
J 0
(-6425 1260);
DISPLAY 0.617021 (-6425 1260);
PAINT ORANGE (-6425 1260);
FORCEPROP 2 LASTPROP $XRERR UNIQUE?
J 0
(-6690 1250);
DISPLAY 0.638298 (-6690 1250);
PAINT MONO (-6690 1250);
DISPLAY INVISIBLE (-6690 1250);
WIRE 16 -1 (-6450 1300)(-5400 1300);
FORCEPROP 2 LAST SIG_NAME TP_CPU0_RSVD_250
J 0
(-6425 1310);
DISPLAY 0.617021 (-6425 1310);
PAINT ORANGE (-6425 1310);
FORCEPROP 2 LASTPROP $XRERR UNIQUE?
J 0
(-6690 1300);
DISPLAY 0.638298 (-6690 1300);
PAINT MONO (-6690 1300);
DISPLAY INVISIBLE (-6690 1300);
WIRE 16 -1 (-5400 1350)(-6450 1350);
FORCEPROP 2 LAST SIG_NAME TP_CPU0_RSVD_251
J 0
(-6425 1360);
DISPLAY 0.617021 (-6425 1360);
PAINT ORANGE (-6425 1360);
FORCEPROP 2 LASTPROP $XRERR UNIQUE?
J 0
(-6690 1350);
DISPLAY 0.638298 (-6690 1350);
PAINT MONO (-6690 1350);
DISPLAY INVISIBLE (-6690 1350);
WIRE 16 -1 (-6450 1800)(-5400 1800);
FORCEPROP 2 LAST SIG_NAME TP_CPU0_RSVD_258
J 0
(-6425 1810);
DISPLAY 0.617021 (-6425 1810);
PAINT ORANGE (-6425 1810);
FORCEPROP 2 LASTPROP $XRERR UNIQUE?
J 0
(-6690 1800);
DISPLAY 0.638298 (-6690 1800);
PAINT MONO (-6690 1800);
DISPLAY INVISIBLE (-6690 1800);
WIRE 16 -1 (-6450 1850)(-5400 1850);
FORCEPROP 2 LAST SIG_NAME TP_CPU0_RSVD_259
J 0
(-6425 1860);
DISPLAY 0.617021 (-6425 1860);
PAINT ORANGE (-6425 1860);
FORCEPROP 2 LASTPROP $XRERR UNIQUE?
J 0
(-6690 1850);
DISPLAY 0.638298 (-6690 1850);
PAINT MONO (-6690 1850);
DISPLAY INVISIBLE (-6690 1850);
WIRE 16 -1 (-5400 2200)(-6450 2200);
FORCEPROP 2 LAST SIG_NAME TP_CPU0_RSVD_265
J 0
(-6425 2210);
DISPLAY 0.617021 (-6425 2210);
PAINT ORANGE (-6425 2210);
FORCEPROP 2 LASTPROP $XRERR UNIQUE?
J 0
(-6690 2200);
DISPLAY 0.638298 (-6690 2200);
PAINT MONO (-6690 2200);
DISPLAY INVISIBLE (-6690 2200);
WIRE 16 -1 (-5400 2250)(-6450 2250);
FORCEPROP 2 LAST SIG_NAME TP_CPU0_RSVD_266
J 0
(-6425 2260);
DISPLAY 0.617021 (-6425 2260);
PAINT ORANGE (-6425 2260);
FORCEPROP 2 LASTPROP $XRERR UNIQUE?
J 0
(-6690 2250);
DISPLAY 0.638298 (-6690 2250);
PAINT MONO (-6690 2250);
DISPLAY INVISIBLE (-6690 2250);
WIRE 16 -1 (-5400 1400)(-6450 1400);
FORCEPROP 2 LAST SIG_NAME TP_CPU0_RSVD_252
J 0
(-6425 1410);
DISPLAY 0.617021 (-6425 1410);
PAINT ORANGE (-6425 1410);
FORCEPROP 2 LASTPROP $XRERR UNIQUE?
J 0
(-6690 1400);
DISPLAY 0.638298 (-6690 1400);
PAINT MONO (-6690 1400);
DISPLAY INVISIBLE (-6690 1400);
WIRE 16 -1 (-6450 1450)(-5400 1450);
FORCEPROP 2 LAST SIG_NAME TP_CPU0_RSVD_253
J 0
(-6425 1460);
DISPLAY 0.617021 (-6425 1460);
PAINT ORANGE (-6425 1460);
FORCEPROP 2 LASTPROP $XRERR UNIQUE?
J 0
(-6690 1450);
DISPLAY 0.638298 (-6690 1450);
PAINT MONO (-6690 1450);
DISPLAY INVISIBLE (-6690 1450);
WIRE 16 -1 (-6450 1500)(-5400 1500);
FORCEPROP 2 LAST SIG_NAME TP_CPU0_RSVD_254
J 0
(-6425 1510);
DISPLAY 0.617021 (-6425 1510);
PAINT ORANGE (-6425 1510);
FORCEPROP 2 LASTPROP $XRERR UNIQUE?
J 0
(-6690 1500);
DISPLAY 0.638298 (-6690 1500);
PAINT MONO (-6690 1500);
DISPLAY INVISIBLE (-6690 1500);
WIRE 16 -1 (-6450 1700)(-5400 1700);
FORCEPROP 2 LAST SIG_NAME TP_CPU0_RSVD_256
J 0
(-6425 1710);
DISPLAY 0.617021 (-6425 1710);
PAINT ORANGE (-6425 1710);
FORCEPROP 2 LASTPROP $XRERR UNIQUE?
J 0
(-6690 1700);
DISPLAY 0.638298 (-6690 1700);
PAINT MONO (-6690 1700);
DISPLAY INVISIBLE (-6690 1700);
WIRE 16 -1 (-5400 1150)(-6450 1150);
FORCEPROP 2 LAST SIG_NAME TP_CPU0_RSVD_248
J 0
(-6425 1160);
DISPLAY 0.617021 (-6425 1160);
PAINT ORANGE (-6425 1160);
FORCEPROP 2 LASTPROP $XRERR UNIQUE?
J 0
(-6690 1150);
DISPLAY 0.638298 (-6690 1150);
PAINT MONO (-6690 1150);
DISPLAY INVISIBLE (-6690 1150);
WIRE 16 -1 (-7100 1750)(-5400 1750);
FORCEPROP 2 LAST SIG_NAME FM_CPU0_RC_ERROR_N
J 0
(-7075 1760);
DISPLAY 0.617021 (-7075 1760);
PAINT ORANGE (-7075 1760);
WIRE 16 -1 (-5400 4100)(-6450 4100);
FORCEPROP 2 LAST SIG_NAME TP_CPU0_RSVD_299
J 0
(-6425 4110);
DISPLAY 0.617021 (-6425 4110);
PAINT ORANGE (-6425 4110);
FORCEPROP 2 LASTPROP $XRERR UNIQUE?
J 0
(-6690 4100);
DISPLAY 0.638298 (-6690 4100);
PAINT MONO (-6690 4100);
DISPLAY INVISIBLE (-6690 4100);
WIRE 16 -1 (-5400 4150)(-6450 4150);
FORCEPROP 2 LAST SIG_NAME TP_CPU0_RSVD_300
J 0
(-6425 4160);
DISPLAY 0.617021 (-6425 4160);
PAINT ORANGE (-6425 4160);
FORCEPROP 2 LASTPROP $XRERR UNIQUE?
J 0
(-6690 4150);
DISPLAY 0.638298 (-6690 4150);
PAINT MONO (-6690 4150);
DISPLAY INVISIBLE (-6690 4150);
WIRE 16 -1 (-5400 4350)(-6450 4350);
FORCEPROP 2 LAST SIG_NAME TP_CPU0_RSVD_304
J 0
(-6425 4360);
DISPLAY 0.617021 (-6425 4360);
PAINT ORANGE (-6425 4360);
FORCEPROP 2 LASTPROP $XRERR UNIQUE?
J 0
(-6690 4350);
DISPLAY 0.638298 (-6690 4350);
PAINT MONO (-6690 4350);
DISPLAY INVISIBLE (-6690 4350);
WIRE 16 -1 (-5400 4300)(-6450 4300);
FORCEPROP 2 LAST SIG_NAME TP_CPU0_RSVD_303
J 0
(-6425 4310);
DISPLAY 0.617021 (-6425 4310);
PAINT ORANGE (-6425 4310);
FORCEPROP 2 LASTPROP $XRERR UNIQUE?
J 0
(-6690 4300);
DISPLAY 0.638298 (-6690 4300);
PAINT MONO (-6690 4300);
DISPLAY INVISIBLE (-6690 4300);
WIRE 16 -1 (-1725 2250)(-2900 2250);
FORCEPROP 2 LAST SIG_NAME TP_CPU0_RSVD_216
J 0
(-2300 2260);
DISPLAY 0.617021 (-2300 2260);
PAINT ORANGE (-2300 2260);
FORCEPROP 2 LASTPROP $XRERR UNIQUE?
J 0
(-1695 2250);
DISPLAY 0.638298 (-1695 2250);
PAINT MONO (-1695 2250);
DISPLAY INVISIBLE (-1695 2250);
WIRE 16 -1 (-1725 2000)(-2900 2000);
FORCEPROP 2 LAST SIG_NAME TP_CPU0_RSVD_214
J 0
(-2300 2010);
DISPLAY 0.617021 (-2300 2010);
PAINT ORANGE (-2300 2010);
FORCEPROP 2 LASTPROP $XRERR UNIQUE?
J 0
(-1695 2000);
DISPLAY 0.638298 (-1695 2000);
PAINT MONO (-1695 2000);
DISPLAY INVISIBLE (-1695 2000);
WIRE 16 -1 (-1775 2350)(-2900 2350);
FORCEPROP 2 LAST SIG_NAME TP_CPU0_RSVD_TEST_5
J 0
(-2300 2360);
DISPLAY 0.617021 (-2300 2360);
PAINT ORANGE (-2300 2360);
FORCEPROP 2 LASTPROP $XRERR UNIQUE?
J 0
(-1745 2350);
DISPLAY 0.638298 (-1745 2350);
PAINT MONO (-1745 2350);
DISPLAY INVISIBLE (-1745 2350);
WIRE 16 -1 (-1725 2500)(-2900 2500);
FORCEPROP 2 LAST SIG_NAME TP_CPU0_RSVD_217
J 0
(-2300 2510);
DISPLAY 0.617021 (-2300 2510);
PAINT ORANGE (-2300 2510);
FORCEPROP 2 LASTPROP $XRERR UNIQUE?
J 0
(-1695 2500);
DISPLAY 0.638298 (-1695 2500);
PAINT MONO (-1695 2500);
DISPLAY INVISIBLE (-1695 2500);
WIRE 16 -1 (-1725 2550)(-2900 2550);
FORCEPROP 2 LAST SIG_NAME TP_CPU0_RSVD_218
J 0
(-2300 2560);
DISPLAY 0.617021 (-2300 2560);
PAINT ORANGE (-2300 2560);
FORCEPROP 2 LASTPROP $XRERR UNIQUE?
J 0
(-1695 2550);
DISPLAY 0.638298 (-1695 2550);
PAINT MONO (-1695 2550);
DISPLAY INVISIBLE (-1695 2550);
WIRE 16 -1 (-1725 2600)(-2900 2600);
FORCEPROP 2 LAST SIG_NAME TP_CPU0_RSVD_219
J 0
(-2300 2610);
DISPLAY 0.617021 (-2300 2610);
PAINT ORANGE (-2300 2610);
FORCEPROP 2 LASTPROP $XRERR UNIQUE?
J 0
(-1695 2600);
DISPLAY 0.638298 (-1695 2600);
PAINT MONO (-1695 2600);
DISPLAY INVISIBLE (-1695 2600);
WIRE 16 -1 (-1725 3350)(-2900 3350);
FORCEPROP 2 LAST SIG_NAME TP_CPU0_RSVD_223
J 0
(-2300 3360);
DISPLAY 0.617021 (-2300 3360);
PAINT ORANGE (-2300 3360);
FORCEPROP 2 LASTPROP $XRERR UNIQUE?
J 0
(-1695 3350);
DISPLAY 0.638298 (-1695 3350);
PAINT MONO (-1695 3350);
DISPLAY INVISIBLE (-1695 3350);
WIRE 16 -1 (-1725 3400)(-2900 3400);
FORCEPROP 2 LAST SIG_NAME TP_CPU0_RSVD_224
J 0
(-2300 3410);
DISPLAY 0.617021 (-2300 3410);
PAINT ORANGE (-2300 3410);
FORCEPROP 2 LASTPROP $XRERR UNIQUE?
J 0
(-1695 3400);
DISPLAY 0.638298 (-1695 3400);
PAINT MONO (-1695 3400);
DISPLAY INVISIBLE (-1695 3400);
WIRE 16 -1 (-1725 3450)(-2900 3450);
FORCEPROP 2 LAST SIG_NAME TP_CPU0_RSVD_225
J 0
(-2300 3460);
DISPLAY 0.617021 (-2300 3460);
PAINT ORANGE (-2300 3460);
FORCEPROP 2 LASTPROP $XRERR UNIQUE?
J 0
(-1695 3450);
DISPLAY 0.638298 (-1695 3450);
PAINT MONO (-1695 3450);
DISPLAY INVISIBLE (-1695 3450);
WIRE 16 -1 (-1725 3500)(-2900 3500);
FORCEPROP 2 LAST SIG_NAME TP_CPU0_RSVD_226
J 0
(-2300 3510);
DISPLAY 0.617021 (-2300 3510);
PAINT ORANGE (-2300 3510);
FORCEPROP 2 LASTPROP $XRERR UNIQUE?
J 0
(-1695 3500);
DISPLAY 0.638298 (-1695 3500);
PAINT MONO (-1695 3500);
DISPLAY INVISIBLE (-1695 3500);
WIRE 16 -1 (-1725 3550)(-2900 3550);
FORCEPROP 2 LAST SIG_NAME TP_CPU0_RSVD_227
J 0
(-2300 3560);
DISPLAY 0.617021 (-2300 3560);
PAINT ORANGE (-2300 3560);
FORCEPROP 2 LASTPROP $XRERR UNIQUE?
J 0
(-1695 3550);
DISPLAY 0.638298 (-1695 3550);
PAINT MONO (-1695 3550);
DISPLAY INVISIBLE (-1695 3550);
WIRE 16 -1 (-1800 1800)(-2900 1800);
FORCEPROP 2 LAST SIG_NAME TP_CPU0_RSVD_212
J 0
(-2300 1810);
DISPLAY 0.617021 (-2300 1810);
PAINT ORANGE (-2300 1810);
FORCEPROP 2 LASTPROP $XRERR UNIQUE?
J 0
(-1770 1800);
DISPLAY 0.638298 (-1770 1800);
PAINT MONO (-1770 1800);
DISPLAY INVISIBLE (-1770 1800);
WIRE 16 -1 (-1725 1750)(-2900 1750);
FORCEPROP 2 LAST SIG_NAME TP_CPU0_RSVD_211
J 0
(-2300 1760);
DISPLAY 0.617021 (-2300 1760);
PAINT ORANGE (-2300 1760);
FORCEPROP 2 LASTPROP $XRERR UNIQUE?
J 0
(-1695 1750);
DISPLAY 0.638298 (-1695 1750);
PAINT MONO (-1695 1750);
DISPLAY INVISIBLE (-1695 1750);
WIRE 16 -1 (-1725 1700)(-2900 1700);
FORCEPROP 2 LAST SIG_NAME TP_CPU0_RSVD_210
J 0
(-2300 1710);
DISPLAY 0.617021 (-2300 1710);
PAINT ORANGE (-2300 1710);
FORCEPROP 2 LASTPROP $XRERR UNIQUE?
J 0
(-1695 1700);
DISPLAY 0.638298 (-1695 1700);
PAINT MONO (-1695 1700);
DISPLAY INVISIBLE (-1695 1700);
WIRE 16 -1 (-1725 1550)(-2900 1550);
FORCEPROP 2 LAST SIG_NAME TP_CPU0_RSVD_208
J 0
(-2300 1560);
DISPLAY 0.617021 (-2300 1560);
PAINT ORANGE (-2300 1560);
FORCEPROP 2 LASTPROP $XRERR UNIQUE?
J 0
(-1695 1550);
DISPLAY 0.638298 (-1695 1550);
PAINT MONO (-1695 1550);
DISPLAY INVISIBLE (-1695 1550);
WIRE 16 -1 (-1725 1000)(-2900 1000);
FORCEPROP 2 LAST SIG_NAME TP_CPU0_RSVD_198
J 0
(-2300 1010);
DISPLAY 0.617021 (-2300 1010);
PAINT ORANGE (-2300 1010);
FORCEPROP 2 LASTPROP $XRERR UNIQUE?
J 0
(-1695 1000);
DISPLAY 0.638298 (-1695 1000);
PAINT MONO (-1695 1000);
DISPLAY INVISIBLE (-1695 1000);
WIRE 16 -1 (-1725 3300)(-2900 3300);
FORCEPROP 2 LAST SIG_NAME TP_CPU0_RSVD_222
J 0
(-2300 3310);
DISPLAY 0.617021 (-2300 3310);
PAINT ORANGE (-2300 3310);
FORCEPROP 2 LASTPROP $XRERR UNIQUE?
J 0
(-1695 3300);
DISPLAY 0.638298 (-1695 3300);
PAINT MONO (-1695 3300);
DISPLAY INVISIBLE (-1695 3300);
WIRE 16 -1 (-1725 3650)(-2900 3650);
FORCEPROP 2 LAST SIG_NAME TP_CPU0_RSVD_228
J 0
(-2300 3660);
DISPLAY 0.617021 (-2300 3660);
PAINT ORANGE (-2300 3660);
FORCEPROP 2 LASTPROP $XRERR UNIQUE?
J 0
(-1695 3650);
DISPLAY 0.638298 (-1695 3650);
PAINT MONO (-1695 3650);
DISPLAY INVISIBLE (-1695 3650);
WIRE 16 -1 (-1725 3700)(-2900 3700);
FORCEPROP 2 LAST SIG_NAME TP_CPU0_RSVD_229
J 0
(-2300 3710);
DISPLAY 0.617021 (-2300 3710);
PAINT ORANGE (-2300 3710);
FORCEPROP 2 LASTPROP $XRERR UNIQUE?
J 0
(-1695 3700);
DISPLAY 0.638298 (-1695 3700);
PAINT MONO (-1695 3700);
DISPLAY INVISIBLE (-1695 3700);
WIRE 16 -1 (-1725 3750)(-2900 3750);
FORCEPROP 2 LAST SIG_NAME TP_CPU0_RSVD_230
J 0
(-2300 3760);
DISPLAY 0.617021 (-2300 3760);
PAINT ORANGE (-2300 3760);
FORCEPROP 2 LASTPROP $XRERR UNIQUE?
J 0
(-1695 3750);
DISPLAY 0.638298 (-1695 3750);
PAINT MONO (-1695 3750);
DISPLAY INVISIBLE (-1695 3750);
WIRE 16 -1 (-1725 3800)(-2900 3800);
FORCEPROP 2 LAST SIG_NAME TP_CPU0_RSVD_231
J 0
(-2300 3810);
DISPLAY 0.617021 (-2300 3810);
PAINT ORANGE (-2300 3810);
FORCEPROP 2 LASTPROP $XRERR UNIQUE?
J 0
(-1695 3800);
DISPLAY 0.638298 (-1695 3800);
PAINT MONO (-1695 3800);
DISPLAY INVISIBLE (-1695 3800);
WIRE 16 -1 (-1725 3850)(-2900 3850);
FORCEPROP 2 LAST SIG_NAME TP_CPU0_RSVD_232
J 0
(-2300 3860);
DISPLAY 0.617021 (-2300 3860);
PAINT ORANGE (-2300 3860);
FORCEPROP 2 LASTPROP $XRERR UNIQUE?
J 0
(-1695 3850);
DISPLAY 0.638298 (-1695 3850);
PAINT MONO (-1695 3850);
DISPLAY INVISIBLE (-1695 3850);
WIRE 16 -1 (-1725 3900)(-2900 3900);
FORCEPROP 2 LAST SIG_NAME TP_CPU0_RSVD_233
J 0
(-2300 3910);
DISPLAY 0.617021 (-2300 3910);
PAINT ORANGE (-2300 3910);
FORCEPROP 2 LASTPROP $XRERR UNIQUE?
J 0
(-1695 3900);
DISPLAY 0.638298 (-1695 3900);
PAINT MONO (-1695 3900);
DISPLAY INVISIBLE (-1695 3900);
WIRE 16 -1 (-1725 3950)(-2900 3950);
FORCEPROP 2 LAST SIG_NAME TP_CPU0_RSVD_234
J 0
(-2300 3960);
DISPLAY 0.617021 (-2300 3960);
PAINT ORANGE (-2300 3960);
FORCEPROP 2 LASTPROP $XRERR UNIQUE?
J 0
(-1695 3950);
DISPLAY 0.638298 (-1695 3950);
PAINT MONO (-1695 3950);
DISPLAY INVISIBLE (-1695 3950);
WIRE 16 -1 (-1725 4050)(-2900 4050);
FORCEPROP 2 LAST SIG_NAME TP_CPU0_RSVD_235
J 0
(-2300 4060);
DISPLAY 0.617021 (-2300 4060);
PAINT ORANGE (-2300 4060);
FORCEPROP 2 LASTPROP $XRERR UNIQUE?
J 0
(-1695 4050);
DISPLAY 0.638298 (-1695 4050);
PAINT MONO (-1695 4050);
DISPLAY INVISIBLE (-1695 4050);
WIRE 16 -1 (-1725 800)(-2900 800);
FORCEPROP 2 LAST SIG_NAME TP_CPU0_RSVD_194
J 0
(-2300 810);
DISPLAY 0.617021 (-2300 810);
PAINT ORANGE (-2300 810);
FORCEPROP 2 LASTPROP $XRERR UNIQUE?
J 0
(-1695 800);
DISPLAY 0.638298 (-1695 800);
PAINT MONO (-1695 800);
DISPLAY INVISIBLE (-1695 800);
WIRE 16 -1 (-1725 1050)(-2900 1050);
FORCEPROP 2 LAST SIG_NAME TP_CPU0_RSVD_199
J 0
(-2300 1060);
DISPLAY 0.617021 (-2300 1060);
PAINT ORANGE (-2300 1060);
FORCEPROP 2 LASTPROP $XRERR UNIQUE?
J 0
(-1695 1050);
DISPLAY 0.638298 (-1695 1050);
PAINT MONO (-1695 1050);
DISPLAY INVISIBLE (-1695 1050);
WIRE 16 -1 (-1725 1350)(-2900 1350);
FORCEPROP 2 LAST SIG_NAME TP_CPU0_RSVD_204
J 0
(-2300 1360);
DISPLAY 0.617021 (-2300 1360);
PAINT ORANGE (-2300 1360);
FORCEPROP 2 LASTPROP $XRERR UNIQUE?
J 0
(-1695 1350);
DISPLAY 0.638298 (-1695 1350);
PAINT MONO (-1695 1350);
DISPLAY INVISIBLE (-1695 1350);
WIRE 16 -1 (-1725 1400)(-2900 1400);
FORCEPROP 2 LAST SIG_NAME TP_CPU0_RSVD_205
J 0
(-2300 1410);
DISPLAY 0.617021 (-2300 1410);
PAINT ORANGE (-2300 1410);
FORCEPROP 2 LASTPROP $XRERR UNIQUE?
J 0
(-1695 1400);
DISPLAY 0.638298 (-1695 1400);
PAINT MONO (-1695 1400);
DISPLAY INVISIBLE (-1695 1400);
WIRE 16 -1 (-2900 2950)(-1750 2950);
FORCEPROP 2 LAST SIG_NAME TP_CPU0_RSVD_TEST_4
J 0
(-2375 2960);
DISPLAY 0.617021 (-2375 2960);
PAINT ORANGE (-2375 2960);
FORCEPROP 2 LASTPROP $XRERR UNIQUE?
J 0
(-1720 2950);
DISPLAY 0.638298 (-1720 2950);
PAINT MONO (-1720 2950);
DISPLAY INVISIBLE (-1720 2950);
WIRE 16 -1 (-2900 3000)(-1750 3000);
FORCEPROP 2 LAST SIG_NAME TP_CPU0_RSVD_TEST_3
J 0
(-2375 3010);
DISPLAY 0.617021 (-2375 3010);
PAINT ORANGE (-2375 3010);
FORCEPROP 2 LASTPROP $XRERR UNIQUE?
J 0
(-1720 3000);
DISPLAY 0.638298 (-1720 3000);
PAINT MONO (-1720 3000);
DISPLAY INVISIBLE (-1720 3000);
WIRE 16 -1 (-1725 2850)(-2900 2850);
FORCEPROP 2 LAST SIG_NAME XDP_CPU_PWR_DEBUG_N
J 0
(-2375 2860);
DISPLAY 0.617021 (-2375 2860);
PAINT ORANGE (-2375 2860);
WIRE 16 -1 (-1725 1850)(-2900 1850);
FORCEPROP 2 LAST SIG_NAME CLK_322M_OSC_CPU0_RC_DN
J 0
(-2310 1860);
DISPLAY 0.617021 (-2310 1860);
PAINT ORANGE (-2310 1860);
WIRE 16 -1 (-1725 2050)(-2900 2050);
FORCEPROP 2 LAST SIG_NAME PD_CPU0_DMIMODE_OVERRIDE
J 2
(-1775 2060);
DISPLAY 0.617021 (-1775 2060);
PAINT ORANGE (-1775 2060);
WIRE 16 -1 (-1725 2650)(-2900 2650);
FORCEPROP 2 LAST SIG_NAME H_CPU0_FIVR_FAULT_G
J 0
(-2300 2660);
DISPLAY 0.617021 (-2300 2660);
PAINT ORANGE (-2300 2660);
WIRE 16 -1 (-1725 2450)(-2900 2450);
FORCEPROP 2 LAST SIG_NAME XDP_PRESENT_N
J 0
(-2300 2460);
DISPLAY 0.617021 (-2300 2460);
PAINT ORANGE (-2300 2460);
WIRE 16 -1 (-1725 2700)(-2900 2700);
FORCEPROP 2 LAST SIG_NAME CLK_322M_OSC_CPU0_RC_DP
J 0
(-2310 2710);
DISPLAY 0.617021 (-2310 2710);
PAINT ORANGE (-2310 2710);
WIRE 16 -1 (-1725 1450)(-2900 1450);
FORCEPROP 2 LAST SIG_NAME CLK_100M_CPU0_RC_REFCLK0_DP
J 0
(-2350 1460);
DISPLAY 0.617021 (-2350 1460);
PAINT ORANGE (-2350 1460);
WIRE 16 -1 (-1725 850)(-2900 850);
FORCEPROP 2 LAST SIG_NAME CLK_100M_CPU0_RC_REFCLK0_DN
J 0
(-2350 860);
DISPLAY 0.617021 (-2350 860);
PAINT ORANGE (-2350 860);
WIRE 16 -1 (-2900 3250)(-1675 3250);
FORCEPROP 2 LAST SIG_NAME VSENSE_P1V8MCP_CPU0_SKT_VSEN
J 0
(-2565 3245);
DISPLAY 0.617021 (-2565 3245);
PAINT ORANGE (-2565 3245);
WIRE 16 -1 (-2900 2200)(-1650 2200);
FORCEPROP 2 LAST SIG_NAME VSENSE_P1V8MCP_CPU0_SKT_VRTN
J 0
(-2490 2195);
DISPLAY 0.617021 (-2490 2195);
PAINT ORANGE (-2490 2195);
WIRE 16 -1 (-575 3050)(-575 2875);
WIRE 16 -1 (-2900 3050)(-575 3050);
FORCEPROP 2 LAST SIG_NAME PD_CPU0_RSVD_TEST_2
J 0
(-2375 3060);
DISPLAY 0.617021 (-2375 3060);
PAINT ORANGE (-2375 3060);
FORCEPROP 2 LASTPROP $XRERR UNIQUE?
J 0
(-2615 3060);
DISPLAY 0.638298 (-2615 3060);
PAINT MONO (-2615 3060);
DISPLAY INVISIBLE (-2615 3060);
WIRE 16 -1 (-300 2875)(-300 3100);
WIRE 16 -1 (-2900 3100)(-300 3100);
FORCEPROP 2 LAST SIG_NAME PD_CPU0_RSVD_TEST_1
J 0
(-2375 3110);
DISPLAY 0.617021 (-2375 3110);
PAINT ORANGE (-2375 3110);
FORCEPROP 2 LASTPROP $XRERR UNIQUE?
J 0
(-2615 3110);
DISPLAY 0.638298 (-2615 3110);
PAINT MONO (-2615 3110);
DISPLAY INVISIBLE (-2615 3110);
WIRE 16 -1 (-1725 4100)(-2900 4100);
FORCEPROP 2 LAST SIG_NAME TP_CPU0_RSVD_236
J 0
(-2300 4110);
DISPLAY 0.617021 (-2300 4110);
PAINT ORANGE (-2300 4110);
FORCEPROP 2 LASTPROP $XRERR UNIQUE?
J 0
(-1695 4100);
DISPLAY 0.638298 (-1695 4100);
PAINT MONO (-1695 4100);
DISPLAY INVISIBLE (-1695 4100);
WIRE 16 -1 (-1725 4150)(-2900 4150);
FORCEPROP 2 LAST SIG_NAME TP_CPU0_RSVD_237
J 0
(-2300 4160);
DISPLAY 0.617021 (-2300 4160);
PAINT ORANGE (-2300 4160);
FORCEPROP 2 LASTPROP $XRERR UNIQUE?
J 0
(-1695 4150);
DISPLAY 0.638298 (-1695 4150);
PAINT MONO (-1695 4150);
DISPLAY INVISIBLE (-1695 4150);
WIRE 16 -1 (-1725 4200)(-2900 4200);
FORCEPROP 2 LAST SIG_NAME TP_CPU0_RSVD_238
J 0
(-2300 4210);
DISPLAY 0.617021 (-2300 4210);
PAINT ORANGE (-2300 4210);
FORCEPROP 2 LASTPROP $XRERR UNIQUE?
J 0
(-1695 4200);
DISPLAY 0.638298 (-1695 4200);
PAINT MONO (-1695 4200);
DISPLAY INVISIBLE (-1695 4200);
WIRE 16 -1 (-1725 4250)(-2900 4250);
FORCEPROP 2 LAST SIG_NAME TP_CPU0_RSVD_239
J 0
(-2300 4260);
DISPLAY 0.617021 (-2300 4260);
PAINT ORANGE (-2300 4260);
FORCEPROP 2 LASTPROP $XRERR UNIQUE?
J 0
(-1695 4250);
DISPLAY 0.638298 (-1695 4250);
PAINT MONO (-1695 4250);
DISPLAY INVISIBLE (-1695 4250);
WIRE 16 -1 (-1725 4300)(-2900 4300);
FORCEPROP 2 LAST SIG_NAME TP_CPU0_RSVD_240
J 0
(-2300 4310);
DISPLAY 0.617021 (-2300 4310);
PAINT ORANGE (-2300 4310);
FORCEPROP 2 LASTPROP $XRERR UNIQUE?
J 0
(-1695 4300);
DISPLAY 0.638298 (-1695 4300);
PAINT MONO (-1695 4300);
DISPLAY INVISIBLE (-1695 4300);
WIRE 16 -1 (-1725 4350)(-2900 4350);
FORCEPROP 2 LAST SIG_NAME TP_CPU0_RSVD_241
J 0
(-2300 4360);
DISPLAY 0.617021 (-2300 4360);
PAINT ORANGE (-2300 4360);
FORCEPROP 2 LASTPROP $XRERR UNIQUE?
J 0
(-1695 4350);
DISPLAY 0.638298 (-1695 4350);
PAINT MONO (-1695 4350);
DISPLAY INVISIBLE (-1695 4350);
DOT 1 (-1100 1100);
DOT 1 (-1100 1500);
DOT 1 (-1100 1650);
DOT 1 (-5575 4250);
DOT 1 (-5575 3900);
DOT 1 (-5575 3950);
DOT 1 (-300 2550);
DOT 1 (-7300 4250);
DOT 1 (-2750 1100);
DOT 1 (-2750 1150);
DOT 1 (-2750 900);
DOT 1 (-2750 1200);
FORCENOTE
BOM_COST=PROC_SOCKET
(-7925 225) 0;
DISPLAY LEFT (-7925 225);
DISPLAY 1.723404 (-7925 225);
PAINT PURPLE (-7925 225);
FORCENOTE
ROOM=CPU0
(-7925 350) 0;
DISPLAY LEFT (-7925 350);
DISPLAY 1.723404 (-7925 350);
PAINT PURPLE (-7925 350);
QUIT
